FILE_TYPE = MACRO_DRAWING;
SET COLOR_WIRE YELLOW;
SET COLOR_PROP ORANGE;
SET COLOR_DOT WHITE;
SET COLOR_ARC YELLOW;
SET COLOR_BODY GREEN;
SET COLOR_NOTE PURPLE;
SET PROP_DISPLAY VALUE;
SET PAGE_NUMBER P322;
FORCEADD UNIVERSAL_GND..1
(-8825 2075);
FORCEPROP 3 LASTPIN (-8825 2125) SIG_NAME GND\g
J 0
(-8815 2135);
DISPLAY 0.659574 (-8815 2135);
PAINT MONO (-8815 2135);
DISPLAY INVISIBLE (-8815 2135);
FORCEPROP 1 LAST PATH I10
J 0
(-8750 2075);
DISPLAY 0.872340 (-8750 2075);
PAINT AQUA (-8750 2075);
DISPLAY INVISIBLE (-8750 2075);
FORCEPROP 2 LAST CDS_LIB logical_power
J 0
(-8825 2075);
DISPLAY INVISIBLE (-8825 2075);
FORCEPROP 1 LAST HDL_POWER GND
J 1
(-8800 2000);
DISPLAY 0.872340 (-8800 2000);
PAINT GREEN (-8800 2000);
DISPLAY INVISIBLE (-8800 2000);
FORCEADD Q_CAP..1
R 2
(-8225 2175);
FORCEPROP 1 LAST PART_NUMBER CH4104K1B00
J 2
(-7900 2025);
DISPLAY 0.510638 (-7900 2025);
DISPLAY INVISIBLE (-7900 2025);
FORCEPROP 1 LAST TOLERANCE 10%
J 2
(-8100 2125);
DISPLAY 0.510638 (-8100 2125);
FORCEPROP 1 LAST VOLTAGE 25V
J 2
(-8100 2175);
DISPLAY 0.510638 (-8100 2175);
FORCEPROP 1 LAST MATERIAL X7R
J 2
(-8100 2075);
DISPLAY 0.510638 (-8100 2075);
FORCEPROP 1 LAST PACK_TYPE 0402
J 2
(-8075 2000);
DISPLAY 0.510638 (-8075 2000);
FORCEPROP 1 LAST VALUE 0.1UF
J 2
(-8050 2225);
DISPLAY 0.510638 (-8050 2225);
FORCEPROP 1 LAST $LOCATION C2252
J 2
(-8050 2250);
DISPLAY 0.638298 (-8050 2250);
FORCEPROP 1 LASTPIN (-8225 2275) $PN 1
J 2
(-8235 2255);
DISPLAY 0.787234 (-8235 2255);
PAINT MONO (-8235 2255);
FORCEPROP 1 LASTPIN (-8225 2075) $PN 2
J 2
(-8235 2055);
DISPLAY 0.787234 (-8235 2055);
PAINT MONO (-8235 2055);
FORCEPROP 2 LAST CDS_LIB pure_quanta
J 0
(-8225 2175);
DISPLAY INVISIBLE (-8225 2175);
FORCEPROP 1 LAST PATH I101
J 2
(-8275 2325);
DISPLAY 0.978723 (-8275 2325);
PAINT WHITE (-8275 2325);
DISPLAY INVISIBLE (-8275 2325);
FORCEPROP 0 LAST CDS_LOCATION C2252
J 0
(-8125 2325);
DISPLAY 1.021277 (-8125 2325);
DISPLAY INVISIBLE (-8125 2325);
FORCEPROP 0 LAST $SEC 1
J 0
(-8125 2325);
DISPLAY 0.680851 (-8125 2325);
PAINT MONO (-8125 2325);
DISPLAY INVISIBLE (-8125 2325);
FORCEPROP 0 LAST CDS_SEC 1
J 0
(-8125 2325);
DISPLAY 1.021277 (-8125 2325);
DISPLAY INVISIBLE (-8125 2325);
FORCEADD UNIVERSAL_GND..1
R 2
(-7850 1900);
FORCEPROP 3 LASTPIN (-7850 1950) SIG_NAME GND\g
J 0
(-7840 1960);
DISPLAY 0.659574 (-7840 1960);
PAINT MONO (-7840 1960);
DISPLAY INVISIBLE (-7840 1960);
FORCEPROP 2 LAST CDS_LIB logical_power
J 0
(-7850 1900);
DISPLAY INVISIBLE (-7850 1900);
FORCEPROP 1 LAST HDL_POWER GND
J 1
(-7875 1825);
DISPLAY 0.872340 (-7875 1825);
PAINT GREEN (-7875 1825);
DISPLAY INVISIBLE (-7875 1825);
FORCEPROP 1 LAST PATH I102
J 2
(-7925 1900);
DISPLAY 0.872340 (-7925 1900);
PAINT AQUA (-7925 1900);
DISPLAY INVISIBLE (-7925 1900);
FORCEADD UNIVERSAL_POWER..1
(-7850 2800);
FORCEPROP 3 LASTPIN (-7850 2750) SIG_NAME P3V3_AUX\g
J 0
(-7840 2760);
DISPLAY 0.659574 (-7840 2760);
PAINT MONO (-7840 2760);
DISPLAY INVISIBLE (-7840 2760);
FORCEPROP 1 LAST HDL_POWER P3V3_AUX
J 1
(-7850 2850);
DISPLAY 0.872340 (-7850 2850);
PAINT GREEN (-7850 2850);
FORCEPROP 1 LAST PATH I105
J 0
(-7800 2825);
DISPLAY 0.872340 (-7800 2825);
PAINT AQUA (-7800 2825);
DISPLAY INVISIBLE (-7800 2825);
FORCEPROP 2 LAST CDS_LIB logical_power
J 0
(-7850 2800);
DISPLAY INVISIBLE (-7850 2800);
FORCEADD Q_CAP..1
R 2
(-8225 100);
FORCEPROP 1 LAST PART_NUMBER CH4104K1B00
J 2
(-7900 -50);
DISPLAY 0.510638 (-7900 -50);
DISPLAY INVISIBLE (-7900 -50);
FORCEPROP 1 LAST MATERIAL X7R
J 2
(-8100 0);
DISPLAY 0.510638 (-8100 0);
FORCEPROP 1 LAST VOLTAGE 25V
J 2
(-8100 100);
DISPLAY 0.510638 (-8100 100);
FORCEPROP 1 LAST TOLERANCE 10%
J 2
(-8100 50);
DISPLAY 0.510638 (-8100 50);
FORCEPROP 1 LAST PACK_TYPE 0402
J 2
(-8075 -75);
DISPLAY 0.510638 (-8075 -75);
FORCEPROP 1 LAST VALUE 0.1UF
J 2
(-8050 150);
DISPLAY 0.510638 (-8050 150);
FORCEPROP 1 LAST $LOCATION C2253
J 2
(-8075 200);
DISPLAY 0.638298 (-8075 200);
FORCEPROP 1 LASTPIN (-8225 200) $PN 1
J 2
(-8235 180);
DISPLAY 0.787234 (-8235 180);
PAINT MONO (-8235 180);
FORCEPROP 1 LASTPIN (-8225 0) $PN 2
J 2
(-8235 -20);
DISPLAY 0.787234 (-8235 -20);
PAINT MONO (-8235 -20);
FORCEPROP 2 LAST CDS_LIB pure_quanta
J 0
(-8225 100);
DISPLAY INVISIBLE (-8225 100);
FORCEPROP 1 LAST PATH I106
J 2
(-8275 250);
DISPLAY 0.978723 (-8275 250);
PAINT WHITE (-8275 250);
DISPLAY INVISIBLE (-8275 250);
FORCEPROP 0 LAST CDS_LOCATION C2253
J 0
(-8125 250);
DISPLAY 1.021277 (-8125 250);
DISPLAY INVISIBLE (-8125 250);
FORCEPROP 0 LAST $SEC 1
J 0
(-8125 250);
DISPLAY 0.680851 (-8125 250);
PAINT MONO (-8125 250);
DISPLAY INVISIBLE (-8125 250);
FORCEPROP 0 LAST CDS_SEC 1
J 0
(-8125 250);
DISPLAY 1.021277 (-8125 250);
DISPLAY INVISIBLE (-8125 250);
FORCEADD UNIVERSAL_GND..1
R 2
(-7850 -175);
FORCEPROP 3 LASTPIN (-7850 -125) SIG_NAME GND\g
J 0
(-7840 -115);
DISPLAY 0.659574 (-7840 -115);
PAINT MONO (-7840 -115);
DISPLAY INVISIBLE (-7840 -115);
FORCEPROP 2 LAST CDS_LIB logical_power
J 0
(-7850 -175);
DISPLAY INVISIBLE (-7850 -175);
FORCEPROP 1 LAST HDL_POWER GND
J 1
(-7875 -250);
DISPLAY 0.872340 (-7875 -250);
PAINT GREEN (-7875 -250);
DISPLAY INVISIBLE (-7875 -250);
FORCEPROP 1 LAST PATH I107
J 2
(-7925 -175);
DISPLAY 0.872340 (-7925 -175);
PAINT AQUA (-7925 -175);
DISPLAY INVISIBLE (-7925 -175);
FORCEADD UNIVERSAL_POWER..1
(-8975 2550);
FORCEPROP 3 LASTPIN (-8975 2500) SIG_NAME P3V3_AUX\g
J 0
(-8965 2510);
DISPLAY 0.659574 (-8965 2510);
PAINT MONO (-8965 2510);
DISPLAY INVISIBLE (-8965 2510);
FORCEPROP 1 LAST HDL_POWER P3V3_AUX
J 1
(-8975 2600);
DISPLAY 0.872340 (-8975 2600);
PAINT GREEN (-8975 2600);
FORCEPROP 1 LAST PATH I11
J 0
(-8925 2575);
DISPLAY 0.872340 (-8925 2575);
PAINT AQUA (-8925 2575);
DISPLAY INVISIBLE (-8925 2575);
FORCEPROP 2 LAST CDS_LIB logical_power
J 0
(-8975 2550);
PAINT RED (-8975 2550);
DISPLAY INVISIBLE (-8975 2550);
FORCEADD UNIVERSAL_POWER..1
(-7850 725);
FORCEPROP 3 LASTPIN (-7850 675) SIG_NAME P3V3_AUX\g
J 0
(-7840 685);
DISPLAY 0.659574 (-7840 685);
PAINT MONO (-7840 685);
DISPLAY INVISIBLE (-7840 685);
FORCEPROP 1 LAST HDL_POWER P3V3_AUX
J 1
(-7850 775);
DISPLAY 0.872340 (-7850 775);
PAINT GREEN (-7850 775);
FORCEPROP 1 LAST PATH I110
J 0
(-7800 750);
DISPLAY 0.872340 (-7800 750);
PAINT AQUA (-7800 750);
DISPLAY INVISIBLE (-7800 750);
FORCEPROP 2 LAST CDS_LIB logical_power
J 0
(-7850 725);
DISPLAY INVISIBLE (-7850 725);
FORCEADD Q_CAP..1
R 2
(-8225 -1800);
FORCEPROP 1 LAST PART_NUMBER CH4104K1B00
J 2
(-7900 -1950);
DISPLAY 0.510638 (-7900 -1950);
DISPLAY INVISIBLE (-7900 -1950);
FORCEPROP 1 LAST VALUE 0.1UF
J 2
(-8050 -1750);
DISPLAY 0.510638 (-8050 -1750);
FORCEPROP 1 LAST PACK_TYPE 0402
J 2
(-8075 -1975);
DISPLAY 0.510638 (-8075 -1975);
FORCEPROP 1 LAST VOLTAGE 25V
J 2
(-8100 -1800);
DISPLAY 0.510638 (-8100 -1800);
FORCEPROP 1 LAST TOLERANCE 10%
J 2
(-8100 -1850);
DISPLAY 0.510638 (-8100 -1850);
FORCEPROP 1 LAST MATERIAL X7R
J 2
(-8100 -1900);
DISPLAY 0.510638 (-8100 -1900);
FORCEPROP 1 LAST $LOCATION C2254
J 2
(-8000 -1700);
DISPLAY 0.978723 (-8000 -1700);
FORCEPROP 1 LASTPIN (-8225 -1700) $PN 1
J 2
(-8235 -1720);
DISPLAY 0.787234 (-8235 -1720);
PAINT MONO (-8235 -1720);
FORCEPROP 1 LASTPIN (-8225 -1900) $PN 2
J 2
(-8235 -1920);
DISPLAY 0.787234 (-8235 -1920);
PAINT MONO (-8235 -1920);
FORCEPROP 2 LAST CDS_LIB pure_quanta
J 0
(-8225 -1800);
DISPLAY INVISIBLE (-8225 -1800);
FORCEPROP 1 LAST PATH I111
J 2
(-8275 -1650);
DISPLAY 0.978723 (-8275 -1650);
PAINT WHITE (-8275 -1650);
DISPLAY INVISIBLE (-8275 -1650);
FORCEPROP 0 LAST CDS_LOCATION C2254
J 0
(-8125 -1650);
DISPLAY 1.021277 (-8125 -1650);
DISPLAY INVISIBLE (-8125 -1650);
FORCEPROP 0 LAST $SEC 1
J 0
(-8125 -1650);
DISPLAY 0.680851 (-8125 -1650);
PAINT MONO (-8125 -1650);
DISPLAY INVISIBLE (-8125 -1650);
FORCEPROP 0 LAST CDS_SEC 1
J 0
(-8125 -1650);
DISPLAY 1.021277 (-8125 -1650);
DISPLAY INVISIBLE (-8125 -1650);
FORCEADD UNIVERSAL_GND..1
R 2
(-7850 -2075);
FORCEPROP 3 LASTPIN (-7850 -2025) SIG_NAME GND\g
J 0
(-7840 -2015);
DISPLAY 0.659574 (-7840 -2015);
PAINT MONO (-7840 -2015);
DISPLAY INVISIBLE (-7840 -2015);
FORCEPROP 2 LAST CDS_LIB logical_power
J 0
(-7850 -2075);
DISPLAY INVISIBLE (-7850 -2075);
FORCEPROP 1 LAST HDL_POWER GND
J 1
(-7875 -2150);
DISPLAY 0.872340 (-7875 -2150);
PAINT GREEN (-7875 -2150);
DISPLAY INVISIBLE (-7875 -2150);
FORCEPROP 1 LAST PATH I112
J 2
(-7925 -2075);
DISPLAY 0.872340 (-7925 -2075);
PAINT AQUA (-7925 -2075);
DISPLAY INVISIBLE (-7925 -2075);
FORCEADD UNIVERSAL_POWER..1
(-7850 -1200);
FORCEPROP 3 LASTPIN (-7850 -1250) SIG_NAME P3V3\g
J 0
(-7840 -1240);
DISPLAY 0.659574 (-7840 -1240);
PAINT MONO (-7840 -1240);
DISPLAY INVISIBLE (-7840 -1240);
FORCEPROP 1 LAST HDL_POWER P3V3
J 1
(-7850 -1150);
DISPLAY 0.872340 (-7850 -1150);
PAINT GREEN (-7850 -1150);
FORCEPROP 2 LAST CDS_LIB logical_power
J 0
(-7850 -1200);
DISPLAY INVISIBLE (-7850 -1200);
FORCEPROP 1 LAST PATH I115
J 0
(-7800 -1175);
DISPLAY 0.872340 (-7800 -1175);
PAINT AQUA (-7800 -1175);
DISPLAY INVISIBLE (-7800 -1175);
FORCEADD OFFPAGE..2
(-6125 1725);
FORCEPROP 2 LAST $XR0 216 
J 0
(-5936 1725);
DISPLAY 0.638298 (-5936 1725);
PAINT MONO (-5936 1725);
FORCEPROP 2 LAST CDS_LIB standard
J 0
(-6125 1725);
DISPLAY INVISIBLE (-6125 1725);
FORCEPROP 2 LAST PATH I116
J 0
(-5950 1800);
DISPLAY 1.021277 (-5950 1800);
DISPLAY INVISIBLE (-5950 1800);
FORCEPROP 1 LAST COMMENT_BODY TRUE
J 0
(-6170 1630);
DISPLAY 0.872340 (-6170 1630);
PAINT GREEN (-6170 1630);
DISPLAY INVISIBLE (-6170 1630);
FORCEPROP 1 LAST OFFPAGE TRUE
J 0
(-5800 1600);
DISPLAY 0.872340 (-5800 1600);
DISPLAY INVISIBLE (-5800 1600);
FORCEADD OFFPAGE..2
(-6125 1675);
FORCEPROP 2 LAST $XR0 216 
J 0
(-5936 1675);
DISPLAY 0.638298 (-5936 1675);
PAINT MONO (-5936 1675);
FORCEPROP 2 LAST CDS_LIB standard
J 0
(-6125 1675);
DISPLAY INVISIBLE (-6125 1675);
FORCEPROP 2 LAST PATH I117
J 0
(-5950 1750);
DISPLAY 1.021277 (-5950 1750);
DISPLAY INVISIBLE (-5950 1750);
FORCEPROP 1 LAST COMMENT_BODY TRUE
J 0
(-6170 1580);
DISPLAY 0.872340 (-6170 1580);
PAINT GREEN (-6170 1580);
DISPLAY INVISIBLE (-6170 1580);
FORCEPROP 1 LAST OFFPAGE TRUE
J 0
(-5800 1550);
DISPLAY 0.872340 (-5800 1550);
DISPLAY INVISIBLE (-5800 1550);
FORCEADD OFFPAGE..2
(-6125 1625);
FORCEPROP 2 LAST $XR0 216 
J 0
(-5936 1625);
DISPLAY 0.638298 (-5936 1625);
PAINT MONO (-5936 1625);
FORCEPROP 2 LAST CDS_LIB standard
J 0
(-6125 1625);
DISPLAY INVISIBLE (-6125 1625);
FORCEPROP 2 LAST PATH I118
J 0
(-5950 1700);
DISPLAY 1.021277 (-5950 1700);
DISPLAY INVISIBLE (-5950 1700);
FORCEPROP 1 LAST COMMENT_BODY TRUE
J 0
(-6170 1530);
DISPLAY 0.872340 (-6170 1530);
PAINT GREEN (-6170 1530);
DISPLAY INVISIBLE (-6170 1530);
FORCEPROP 1 LAST OFFPAGE TRUE
J 0
(-5800 1500);
DISPLAY 0.872340 (-5800 1500);
DISPLAY INVISIBLE (-5800 1500);
FORCEADD OFFPAGE..2
(-6125 1575);
FORCEPROP 2 LAST $XR0 216 
J 0
(-5936 1575);
DISPLAY 0.638298 (-5936 1575);
PAINT MONO (-5936 1575);
FORCEPROP 2 LAST CDS_LIB standard
J 0
(-6125 1575);
DISPLAY INVISIBLE (-6125 1575);
FORCEPROP 2 LAST PATH I119
J 0
(-5950 1650);
DISPLAY 1.021277 (-5950 1650);
DISPLAY INVISIBLE (-5950 1650);
FORCEPROP 1 LAST COMMENT_BODY TRUE
J 0
(-6170 1480);
DISPLAY 0.872340 (-6170 1480);
PAINT GREEN (-6170 1480);
DISPLAY INVISIBLE (-6170 1480);
FORCEPROP 1 LAST OFFPAGE TRUE
J 0
(-5800 1450);
DISPLAY 0.872340 (-5800 1450);
DISPLAY INVISIBLE (-5800 1450);
FORCEADD OFFPAGE..2
(-6125 -500);
FORCEPROP 2 LAST $XR0 216 
J 0
(-5936 -500);
DISPLAY 0.638298 (-5936 -500);
PAINT MONO (-5936 -500);
FORCEPROP 1 LAST OFFPAGE TRUE
J 0
(-5800 -625);
DISPLAY 0.872340 (-5800 -625);
DISPLAY INVISIBLE (-5800 -625);
FORCEPROP 1 LAST COMMENT_BODY TRUE
J 0
(-6170 -595);
DISPLAY 0.872340 (-6170 -595);
PAINT GREEN (-6170 -595);
DISPLAY INVISIBLE (-6170 -595);
FORCEPROP 2 LAST PATH I120
J 0
(-5950 -425);
DISPLAY 1.021277 (-5950 -425);
DISPLAY INVISIBLE (-5950 -425);
FORCEPROP 2 LAST CDS_LIB standard
J 0
(-6125 -500);
DISPLAY INVISIBLE (-6125 -500);
FORCEADD OFFPAGE..2
(-6125 -450);
FORCEPROP 2 LAST $XR0 216 
J 0
(-5936 -450);
DISPLAY 0.638298 (-5936 -450);
PAINT MONO (-5936 -450);
FORCEPROP 1 LAST OFFPAGE TRUE
J 0
(-5800 -575);
DISPLAY 0.872340 (-5800 -575);
DISPLAY INVISIBLE (-5800 -575);
FORCEPROP 1 LAST COMMENT_BODY TRUE
J 0
(-6170 -545);
DISPLAY 0.872340 (-6170 -545);
PAINT GREEN (-6170 -545);
DISPLAY INVISIBLE (-6170 -545);
FORCEPROP 2 LAST PATH I121
J 0
(-5950 -375);
DISPLAY 1.021277 (-5950 -375);
DISPLAY INVISIBLE (-5950 -375);
FORCEPROP 2 LAST CDS_LIB standard
J 0
(-6125 -450);
DISPLAY INVISIBLE (-6125 -450);
FORCEADD OFFPAGE..2
(-6125 -400);
FORCEPROP 2 LAST $XR0 216 
J 0
(-5936 -400);
DISPLAY 0.638298 (-5936 -400);
PAINT MONO (-5936 -400);
FORCEPROP 1 LAST OFFPAGE TRUE
J 0
(-5800 -525);
DISPLAY 0.872340 (-5800 -525);
DISPLAY INVISIBLE (-5800 -525);
FORCEPROP 1 LAST COMMENT_BODY TRUE
J 0
(-6170 -495);
DISPLAY 0.872340 (-6170 -495);
PAINT GREEN (-6170 -495);
DISPLAY INVISIBLE (-6170 -495);
FORCEPROP 2 LAST PATH I122
J 0
(-5950 -325);
DISPLAY 1.021277 (-5950 -325);
DISPLAY INVISIBLE (-5950 -325);
FORCEPROP 2 LAST CDS_LIB standard
J 0
(-6125 -400);
DISPLAY INVISIBLE (-6125 -400);
FORCEADD OFFPAGE..2
(-6125 -350);
FORCEPROP 2 LAST $XR0 216 
J 0
(-5936 -350);
DISPLAY 0.638298 (-5936 -350);
PAINT MONO (-5936 -350);
FORCEPROP 1 LAST OFFPAGE TRUE
J 0
(-5800 -475);
DISPLAY 0.872340 (-5800 -475);
DISPLAY INVISIBLE (-5800 -475);
FORCEPROP 1 LAST COMMENT_BODY TRUE
J 0
(-6170 -445);
DISPLAY 0.872340 (-6170 -445);
PAINT GREEN (-6170 -445);
DISPLAY INVISIBLE (-6170 -445);
FORCEPROP 2 LAST PATH I123
J 0
(-5950 -275);
DISPLAY 1.021277 (-5950 -275);
DISPLAY INVISIBLE (-5950 -275);
FORCEPROP 2 LAST CDS_LIB standard
J 0
(-6125 -350);
DISPLAY INVISIBLE (-6125 -350);
FORCEADD OFFPAGE..2
(-4800 -2300);
FORCEPROP 2 LAST $XR0 216 
J 0
(-4611 -2300);
DISPLAY 0.638298 (-4611 -2300);
PAINT MONO (-4611 -2300);
FORCEPROP 2 LAST CDS_LIB standard
J 0
(-4800 -2300);
DISPLAY INVISIBLE (-4800 -2300);
FORCEPROP 2 LAST PATH I126
J 0
(-4625 -2225);
DISPLAY 1.021277 (-4625 -2225);
DISPLAY INVISIBLE (-4625 -2225);
FORCEPROP 1 LAST COMMENT_BODY TRUE
J 0
(-4845 -2395);
DISPLAY 0.872340 (-4845 -2395);
PAINT GREEN (-4845 -2395);
DISPLAY INVISIBLE (-4845 -2395);
FORCEPROP 1 LAST OFFPAGE TRUE
J 0
(-4475 -2425);
DISPLAY 0.872340 (-4475 -2425);
DISPLAY INVISIBLE (-4475 -2425);
FORCEADD Q_RES..2
(-7850 2550);
FORCEPROP 1 LAST PART_NUMBER CS24322FB03
J 0
(-7810 2425);
DISPLAY 0.638298 (-7810 2425);
DISPLAY INVISIBLE (-7810 2425);
FORCEPROP 1 LAST VALUE 4.32K
J 0
(-7805 2625);
DISPLAY 0.638298 (-7805 2625);
FORCEPROP 1 LAST TOLERANCE 1%
J 0
(-7805 2575);
DISPLAY 0.638298 (-7805 2575);
FORCEPROP 1 LAST WATTAGE 1/16W
J 0
(-7810 2525);
DISPLAY 0.638298 (-7810 2525);
FORCEPROP 1 LAST MATERIAL CHIP
J 0
(-7810 2475);
DISPLAY 0.638298 (-7810 2475);
FORCEPROP 1 LAST PACK_TYPE 0402LF
J 0
(-7810 2375);
DISPLAY 0.638298 (-7810 2375);
FORCEPROP 1 LAST LOCATION R4036
J 0
(-7805 2675);
DISPLAY 0.787234 (-7805 2675);
FORCEPROP 1 LASTPIN (-7850 2650) $PN 1
J 0
(-7845 2612);
DISPLAY 0.787234 (-7845 2612);
PAINT MONO (-7845 2612);
FORCEPROP 1 LASTPIN (-7850 2450) $PN 2
J 0
(-7845 2460);
DISPLAY 0.787234 (-7845 2460);
PAINT MONO (-7845 2460);
FORCEPROP 2 LAST CDS_LIB pure_quanta
J 0
(-7850 2550);
DISPLAY INVISIBLE (-7850 2550);
FORCEPROP 1 LAST PATH I128
J 0
(-7800 2725);
DISPLAY 0.978723 (-7800 2725);
PAINT WHITE (-7800 2725);
DISPLAY INVISIBLE (-7800 2725);
FORCEPROP 0 LAST $SEC 1
J 0
(-7800 2725);
DISPLAY 0.680851 (-7800 2725);
PAINT MONO (-7800 2725);
DISPLAY INVISIBLE (-7800 2725);
FORCEPROP 0 LAST CDS_SEC 1
J 0
(-7800 2725);
DISPLAY 1.021277 (-7800 2725);
DISPLAY INVISIBLE (-7800 2725);
FORCEADD Q_RES..2
(-7850 2175);
FORCEPROP 1 LAST PART_NUMBER CS21002FB06
J 0
(-7810 2050);
DISPLAY 0.638298 (-7810 2050);
DISPLAY INVISIBLE (-7810 2050);
FORCEPROP 1 LAST VALUE 1K
J 0
(-7805 2250);
DISPLAY 0.638298 (-7805 2250);
FORCEPROP 1 LAST TOLERANCE 1%
J 0
(-7805 2200);
DISPLAY 0.638298 (-7805 2200);
FORCEPROP 1 LAST PACK_TYPE 0402LF
J 0
(-7810 2000);
DISPLAY 0.638298 (-7810 2000);
FORCEPROP 1 LAST MATERIAL CHIP
J 0
(-7810 2100);
DISPLAY 0.638298 (-7810 2100);
FORCEPROP 1 LAST WATTAGE 1/16W
J 0
(-7810 2150);
DISPLAY 0.638298 (-7810 2150);
FORCEPROP 1 LAST LOCATION R4039
J 0
(-7805 2300);
DISPLAY 0.787234 (-7805 2300);
FORCEPROP 1 LASTPIN (-7850 2275) $PN 1
J 0
(-7845 2237);
DISPLAY 0.787234 (-7845 2237);
PAINT MONO (-7845 2237);
FORCEPROP 1 LASTPIN (-7850 2075) $PN 2
J 0
(-7845 2085);
DISPLAY 0.787234 (-7845 2085);
PAINT MONO (-7845 2085);
FORCEPROP 2 LAST CDS_LIB pure_quanta
J 0
(-7850 2175);
DISPLAY INVISIBLE (-7850 2175);
FORCEPROP 1 LAST PATH I129
J 0
(-7800 2350);
DISPLAY 0.978723 (-7800 2350);
PAINT WHITE (-7800 2350);
DISPLAY INVISIBLE (-7800 2350);
FORCEPROP 0 LAST $SEC 1
J 0
(-7800 2350);
DISPLAY 0.680851 (-7800 2350);
PAINT MONO (-7800 2350);
DISPLAY INVISIBLE (-7800 2350);
FORCEPROP 0 LAST CDS_SEC 1
J 0
(-7800 2350);
DISPLAY 1.021277 (-7800 2350);
DISPLAY INVISIBLE (-7800 2350);
FORCEADD Q_RES..2
(-7850 475);
FORCEPROP 1 LAST PART_NUMBER CS24322FB03
J 0
(-7810 350);
DISPLAY 0.638298 (-7810 350);
DISPLAY INVISIBLE (-7810 350);
FORCEPROP 1 LAST MATERIAL CHIP
J 0
(-7810 400);
DISPLAY 0.638298 (-7810 400);
FORCEPROP 1 LAST VALUE 4.32K
J 0
(-7805 550);
DISPLAY 0.638298 (-7805 550);
FORCEPROP 1 LAST TOLERANCE 1%
J 0
(-7805 500);
DISPLAY 0.638298 (-7805 500);
FORCEPROP 1 LAST WATTAGE 1/16W
J 0
(-7810 450);
DISPLAY 0.638298 (-7810 450);
FORCEPROP 1 LAST PACK_TYPE 0402LF
J 0
(-7810 300);
DISPLAY 0.638298 (-7810 300);
FORCEPROP 1 LAST LOCATION R4037
J 0
(-7805 600);
DISPLAY 0.638298 (-7805 600);
FORCEPROP 1 LASTPIN (-7850 575) $PN 1
J 0
(-7845 537);
DISPLAY 0.787234 (-7845 537);
PAINT MONO (-7845 537);
FORCEPROP 1 LASTPIN (-7850 375) $PN 2
J 0
(-7845 385);
DISPLAY 0.787234 (-7845 385);
PAINT MONO (-7845 385);
FORCEPROP 1 LAST PATH I130
J 0
(-7800 650);
DISPLAY 0.978723 (-7800 650);
PAINT WHITE (-7800 650);
DISPLAY INVISIBLE (-7800 650);
FORCEPROP 2 LAST CDS_LIB pure_quanta
J 0
(-7850 475);
DISPLAY INVISIBLE (-7850 475);
FORCEPROP 0 LAST $SEC 1
J 0
(-7800 650);
DISPLAY 0.680851 (-7800 650);
PAINT MONO (-7800 650);
DISPLAY INVISIBLE (-7800 650);
FORCEPROP 0 LAST CDS_SEC 1
J 0
(-7800 650);
DISPLAY 1.021277 (-7800 650);
DISPLAY INVISIBLE (-7800 650);
FORCEADD Q_RES..2
(-7850 100);
FORCEPROP 1 LAST PART_NUMBER CS21002FB06
J 0
(-7810 -25);
DISPLAY 0.638298 (-7810 -25);
DISPLAY INVISIBLE (-7810 -25);
FORCEPROP 1 LAST VALUE 1K
J 0
(-7805 175);
DISPLAY 0.638298 (-7805 175);
FORCEPROP 1 LAST TOLERANCE 1%
J 0
(-7805 125);
DISPLAY 0.638298 (-7805 125);
FORCEPROP 1 LAST WATTAGE 1/16W
J 0
(-7810 75);
DISPLAY 0.638298 (-7810 75);
FORCEPROP 1 LAST MATERIAL CHIP
J 0
(-7810 25);
DISPLAY 0.638298 (-7810 25);
FORCEPROP 1 LAST PACK_TYPE 0402LF
J 0
(-7810 -75);
DISPLAY 0.638298 (-7810 -75);
FORCEPROP 1 LAST LOCATION R4040
J 0
(-7805 225);
DISPLAY 0.638298 (-7805 225);
FORCEPROP 1 LASTPIN (-7850 200) $PN 1
J 0
(-7845 162);
DISPLAY 0.787234 (-7845 162);
PAINT MONO (-7845 162);
FORCEPROP 1 LASTPIN (-7850 0) $PN 2
J 0
(-7845 10);
DISPLAY 0.787234 (-7845 10);
PAINT MONO (-7845 10);
FORCEPROP 1 LAST PATH I131
J 0
(-7800 275);
DISPLAY 0.978723 (-7800 275);
PAINT WHITE (-7800 275);
DISPLAY INVISIBLE (-7800 275);
FORCEPROP 2 LAST CDS_LIB pure_quanta
J 0
(-7850 100);
DISPLAY INVISIBLE (-7850 100);
FORCEPROP 0 LAST $SEC 1
J 0
(-7800 275);
DISPLAY 0.680851 (-7800 275);
PAINT MONO (-7800 275);
DISPLAY INVISIBLE (-7800 275);
FORCEPROP 0 LAST CDS_SEC 1
J 0
(-7800 275);
DISPLAY 1.021277 (-7800 275);
DISPLAY INVISIBLE (-7800 275);
FORCEADD UNIVERSAL_POWER..1
(-12050 -850);
FORCEPROP 3 LASTPIN (-12050 -900) SIG_NAME PVNN_TERM_CPU0\g
J 0
(-12040 -890);
DISPLAY 0.659574 (-12040 -890);
PAINT MONO (-12040 -890);
DISPLAY INVISIBLE (-12040 -890);
FORCEPROP 1 LAST HDL_POWER PVNN_TERM_CPU0
J 1
(-12050 -800);
DISPLAY 0.872340 (-12050 -800);
PAINT GREEN (-12050 -800);
FORCEPROP 1 LAST PATH I132
J 0
(-12000 -825);
DISPLAY 0.872340 (-12000 -825);
PAINT AQUA (-12000 -825);
DISPLAY INVISIBLE (-12000 -825);
FORCEPROP 2 LAST CDS_LIB logical_power
J 0
(-12050 -850);
DISPLAY INVISIBLE (-12050 -850);
FORCEADD Q_RES..1
(-12400 -3100);
FORCEPROP 1 LAST PART_NUMBER CS00002JB13
J 0
(-12525 -3250);
DISPLAY 0.510638 (-12525 -3250);
DISPLAY INVISIBLE (-12525 -3250);
FORCEPROP 1 LAST TOLERANCE 5%
J 0
(-12225 -3100);
DISPLAY 0.638298 (-12225 -3100);
FORCEPROP 1 LAST VALUE 0
J 2
(-12250 -3100);
DISPLAY 0.638298 (-12250 -3100);
FORCEPROP 1 LAST $LOCATION R344
J 0
(-12600 -3100);
DISPLAY 0.638298 (-12600 -3100);
FORCEPROP 1 LASTPIN (-12500 -3100) $PN 1
J 0
(-12488 -3088);
DISPLAY 0.787234 (-12488 -3088);
FORCEPROP 1 LASTPIN (-12300 -3100) $PN 2
J 0
(-12338 -3088);
DISPLAY 0.787234 (-12338 -3088);
FORCEPROP 1 LAST PACK_TYPE 0402LF
J 0
(-12150 -3100);
DISPLAY 0.638298 (-12150 -3100);
DISPLAY INVISIBLE (-12150 -3100);
FORCEPROP 2 LAST CDS_LIB pure_quanta
J 0
(-12400 -3100);
PAINT MONO (-12400 -3100);
DISPLAY INVISIBLE (-12400 -3100);
FORCEPROP 1 LAST MATERIAL CHIP
J 0
(-12400 -3250);
DISPLAY 0.978723 (-12400 -3250);
DISPLAY INVISIBLE (-12400 -3250);
FORCEPROP 1 LAST WATTAGE 1/16W
J 2
(-12425 -3250);
DISPLAY 0.978723 (-12425 -3250);
DISPLAY INVISIBLE (-12425 -3250);
FORCEPROP 1 LAST PATH I157
J 0
(-12450 -2950);
DISPLAY 0.978723 (-12450 -2950);
PAINT WHITE (-12450 -2950);
DISPLAY INVISIBLE (-12450 -2950);
FORCEPROP 2 LAST CDS_LOCATION R344
J 0
(-12450 -2900);
DISPLAY 1.021277 (-12450 -2900);
DISPLAY INVISIBLE (-12450 -2900);
FORCEPROP 2 LAST $SEC 1
J 0
(-12450 -2900);
DISPLAY 0.680851 (-12450 -2900);
PAINT MONO (-12450 -2900);
DISPLAY INVISIBLE (-12450 -2900);
FORCEPROP 2 LAST CDS_SEC 1
J 0
(-12450 -2900);
DISPLAY 1.021277 (-12450 -2900);
DISPLAY INVISIBLE (-12450 -2900);
FORCEADD Q_RES..1
(-12400 -3150);
FORCEPROP 1 LAST PART_NUMBER CS00002JB13
J 0
(-12525 -3300);
DISPLAY 0.510638 (-12525 -3300);
DISPLAY INVISIBLE (-12525 -3300);
FORCEPROP 1 LAST TOLERANCE 5%
J 0
(-12225 -3150);
DISPLAY 0.638298 (-12225 -3150);
FORCEPROP 1 LAST VALUE 0
J 2
(-12250 -3150);
DISPLAY 0.638298 (-12250 -3150);
FORCEPROP 1 LAST $LOCATION R345
J 0
(-12600 -3150);
DISPLAY 0.638298 (-12600 -3150);
FORCEPROP 1 LASTPIN (-12500 -3150) $PN 1
J 0
(-12488 -3138);
DISPLAY 0.787234 (-12488 -3138);
FORCEPROP 1 LASTPIN (-12300 -3150) $PN 2
J 0
(-12338 -3138);
DISPLAY 0.787234 (-12338 -3138);
FORCEPROP 2 LAST CDS_LIB pure_quanta
J 0
(-12400 -3150);
PAINT MONO (-12400 -3150);
DISPLAY INVISIBLE (-12400 -3150);
FORCEPROP 1 LAST WATTAGE 1/16W
J 2
(-12425 -3300);
DISPLAY 0.978723 (-12425 -3300);
DISPLAY INVISIBLE (-12425 -3300);
FORCEPROP 1 LAST MATERIAL CHIP
J 0
(-12400 -3300);
DISPLAY 0.978723 (-12400 -3300);
DISPLAY INVISIBLE (-12400 -3300);
FORCEPROP 1 LAST PACK_TYPE 0402LF
J 0
(-12150 -3150);
DISPLAY 0.638298 (-12150 -3150);
DISPLAY INVISIBLE (-12150 -3150);
FORCEPROP 1 LAST PATH I158
J 0
(-12450 -3000);
DISPLAY 0.978723 (-12450 -3000);
PAINT WHITE (-12450 -3000);
DISPLAY INVISIBLE (-12450 -3000);
FORCEPROP 2 LAST CDS_LOCATION R345
J 0
(-12450 -2950);
DISPLAY 1.021277 (-12450 -2950);
DISPLAY INVISIBLE (-12450 -2950);
FORCEPROP 2 LAST $SEC 1
J 0
(-12450 -2950);
DISPLAY 0.680851 (-12450 -2950);
PAINT MONO (-12450 -2950);
DISPLAY INVISIBLE (-12450 -2950);
FORCEPROP 2 LAST CDS_SEC 1
J 0
(-12450 -2950);
DISPLAY 1.021277 (-12450 -2950);
DISPLAY INVISIBLE (-12450 -2950);
FORCEADD Q_RES..1
(-12450 -1325);
FORCEPROP 1 LAST PART_NUMBER CS00002JB13
J 0
(-12550 -1250);
DISPLAY 0.510638 (-12550 -1250);
DISPLAY INVISIBLE (-12550 -1250);
FORCEPROP 1 LAST WATTAGE 1/16W
J 2
(-12325 -1200);
DISPLAY 0.510638 (-12325 -1200);
FORCEPROP 1 LAST MATERIAL CHIP
J 0
(-12550 -1200);
DISPLAY 0.510638 (-12550 -1200);
FORCEPROP 1 LAST VALUE 0
J 2
(-12300 -1325);
DISPLAY 0.638298 (-12300 -1325);
FORCEPROP 1 LAST PACK_TYPE 0402LF
J 0
(-12300 -1200);
DISPLAY 0.510638 (-12300 -1200);
FORCEPROP 1 LAST TOLERANCE 5%
J 0
(-12275 -1325);
DISPLAY 0.638298 (-12275 -1325);
FORCEPROP 1 LAST $LOCATION R336
J 0
(-12650 -1325);
DISPLAY 0.638298 (-12650 -1325);
FORCEPROP 1 LASTPIN (-12550 -1325) $PN 1
J 0
(-12538 -1313);
DISPLAY 0.787234 (-12538 -1313);
FORCEPROP 1 LASTPIN (-12350 -1325) $PN 2
J 0
(-12388 -1313);
DISPLAY 0.787234 (-12388 -1313);
FORCEPROP 1 LAST PATH I159
J 0
(-12500 -1175);
DISPLAY 0.978723 (-12500 -1175);
PAINT WHITE (-12500 -1175);
DISPLAY INVISIBLE (-12500 -1175);
FORCEPROP 2 LAST CDS_LIB pure_quanta
J 0
(-12450 -1325);
PAINT MONO (-12450 -1325);
DISPLAY INVISIBLE (-12450 -1325);
FORCEPROP 2 LAST CDS_LOCATION R336
J 0
(-12500 -1125);
DISPLAY 1.021277 (-12500 -1125);
DISPLAY INVISIBLE (-12500 -1125);
FORCEPROP 2 LAST $SEC 1
J 0
(-12500 -1125);
DISPLAY 0.680851 (-12500 -1125);
PAINT MONO (-12500 -1125);
DISPLAY INVISIBLE (-12500 -1125);
FORCEPROP 2 LAST CDS_SEC 1
J 0
(-12500 -1125);
DISPLAY 1.021277 (-12500 -1125);
DISPLAY INVISIBLE (-12500 -1125);
FORCEADD Q_RES..1
(-12450 -1375);
FORCEPROP 1 LAST PART_NUMBER CS00002JB13
J 0
(-12575 -1525);
DISPLAY 0.510638 (-12575 -1525);
DISPLAY INVISIBLE (-12575 -1525);
FORCEPROP 1 LAST VALUE 0
J 2
(-12300 -1375);
DISPLAY 0.638298 (-12300 -1375);
FORCEPROP 1 LAST TOLERANCE 5%
J 0
(-12275 -1375);
DISPLAY 0.638298 (-12275 -1375);
FORCEPROP 1 LAST $LOCATION R337
J 0
(-12650 -1375);
DISPLAY 0.638298 (-12650 -1375);
FORCEPROP 1 LASTPIN (-12550 -1375) $PN 1
J 0
(-12538 -1363);
DISPLAY 0.787234 (-12538 -1363);
FORCEPROP 1 LASTPIN (-12350 -1375) $PN 2
J 0
(-12388 -1363);
DISPLAY 0.787234 (-12388 -1363);
FORCEPROP 1 LAST WATTAGE 1/16W
J 2
(-12475 -1525);
DISPLAY 0.978723 (-12475 -1525);
DISPLAY INVISIBLE (-12475 -1525);
FORCEPROP 1 LAST MATERIAL CHIP
J 0
(-12450 -1525);
DISPLAY 0.978723 (-12450 -1525);
DISPLAY INVISIBLE (-12450 -1525);
FORCEPROP 1 LAST PACK_TYPE 0402LF
J 0
(-12200 -1375);
DISPLAY 0.638298 (-12200 -1375);
DISPLAY INVISIBLE (-12200 -1375);
FORCEPROP 2 LAST CDS_LIB pure_quanta
J 0
(-12450 -1375);
PAINT MONO (-12450 -1375);
DISPLAY INVISIBLE (-12450 -1375);
FORCEPROP 1 LAST PATH I160
J 0
(-12500 -1225);
DISPLAY 0.978723 (-12500 -1225);
PAINT WHITE (-12500 -1225);
DISPLAY INVISIBLE (-12500 -1225);
FORCEPROP 2 LAST CDS_LOCATION R337
J 0
(-12500 -1175);
DISPLAY 1.021277 (-12500 -1175);
DISPLAY INVISIBLE (-12500 -1175);
FORCEPROP 2 LAST $SEC 1
J 0
(-12500 -1175);
DISPLAY 0.680851 (-12500 -1175);
PAINT MONO (-12500 -1175);
DISPLAY INVISIBLE (-12500 -1175);
FORCEPROP 2 LAST CDS_SEC 1
J 0
(-12500 -1175);
DISPLAY 1.021277 (-12500 -1175);
DISPLAY INVISIBLE (-12500 -1175);
FORCEADD OFFPAGE..1
(-13275 -1375);
FORCEPROP 2 LAST $XR0 45 
J 0
(-13526 -1375);
DISPLAY 0.638298 (-13526 -1375);
PAINT MONO (-13526 -1375);
FORCEPROP 2 LAST CDS_LIB standard
J 0
(-13275 -1375);
PAINT MONO (-13275 -1375);
DISPLAY INVISIBLE (-13275 -1375);
FORCEPROP 1 LAST OFFPAGE TRUE
J 0
(-12950 -1500);
DISPLAY 0.872340 (-12950 -1500);
PAINT GREEN (-12950 -1500);
DISPLAY INVISIBLE (-12950 -1500);
FORCEPROP 1 LAST COMMENT_BODY TRUE
J 0
(-13150 -1475);
DISPLAY 0.872340 (-13150 -1475);
PAINT GREEN (-13150 -1475);
DISPLAY INVISIBLE (-13150 -1475);
FORCEPROP 2 LAST PATH I161
J 0
(-13525 -1325);
DISPLAY 1.021277 (-13525 -1325);
DISPLAY INVISIBLE (-13525 -1325);
FORCEADD OFFPAGE..1
(-13275 -1325);
FORCEPROP 2 LAST $XR0 14 
J 0
(-13526 -1325);
DISPLAY 0.638298 (-13526 -1325);
PAINT MONO (-13526 -1325);
FORCEPROP 2 LAST PATH I162
J 0
(-13525 -1275);
DISPLAY 1.021277 (-13525 -1275);
DISPLAY INVISIBLE (-13525 -1275);
FORCEPROP 1 LAST COMMENT_BODY TRUE
J 0
(-13150 -1425);
DISPLAY 0.872340 (-13150 -1425);
PAINT GREEN (-13150 -1425);
DISPLAY INVISIBLE (-13150 -1425);
FORCEPROP 1 LAST OFFPAGE TRUE
J 0
(-12950 -1450);
DISPLAY 0.872340 (-12950 -1450);
PAINT GREEN (-12950 -1450);
DISPLAY INVISIBLE (-12950 -1450);
FORCEPROP 2 LAST CDS_LIB standard
J 0
(-13275 -1325);
PAINT MONO (-13275 -1325);
DISPLAY INVISIBLE (-13275 -1325);
FORCEADD Q_RES..1
(-12475 -2300);
FORCEPROP 1 LAST PART_NUMBER CS00002JB13
J 0
(-12600 -2450);
DISPLAY 0.510638 (-12600 -2450);
DISPLAY INVISIBLE (-12600 -2450);
FORCEPROP 1 LAST VALUE 0
J 2
(-12325 -2300);
DISPLAY 0.638298 (-12325 -2300);
FORCEPROP 1 LAST TOLERANCE 5%
J 0
(-12300 -2300);
DISPLAY 0.638298 (-12300 -2300);
FORCEPROP 1 LAST $LOCATION R341
J 0
(-12675 -2300);
DISPLAY 0.638298 (-12675 -2300);
FORCEPROP 1 LASTPIN (-12575 -2300) $PN 1
J 0
(-12563 -2288);
DISPLAY 0.787234 (-12563 -2288);
FORCEPROP 1 LASTPIN (-12375 -2300) $PN 2
J 0
(-12413 -2288);
DISPLAY 0.787234 (-12413 -2288);
FORCEPROP 1 LAST PATH I163
J 0
(-12525 -2150);
DISPLAY 0.978723 (-12525 -2150);
PAINT WHITE (-12525 -2150);
DISPLAY INVISIBLE (-12525 -2150);
FORCEPROP 1 LAST WATTAGE 1/16W
J 2
(-12500 -2450);
DISPLAY 0.978723 (-12500 -2450);
DISPLAY INVISIBLE (-12500 -2450);
FORCEPROP 1 LAST MATERIAL CHIP
J 0
(-12475 -2450);
DISPLAY 0.978723 (-12475 -2450);
DISPLAY INVISIBLE (-12475 -2450);
FORCEPROP 2 LAST CDS_LIB pure_quanta
J 0
(-12475 -2300);
PAINT MONO (-12475 -2300);
DISPLAY INVISIBLE (-12475 -2300);
FORCEPROP 1 LAST PACK_TYPE 0402LF
J 0
(-12225 -2300);
DISPLAY 0.638298 (-12225 -2300);
DISPLAY INVISIBLE (-12225 -2300);
FORCEPROP 2 LAST CDS_LOCATION R341
J 0
(-12525 -2100);
DISPLAY 1.021277 (-12525 -2100);
DISPLAY INVISIBLE (-12525 -2100);
FORCEPROP 2 LAST $SEC 1
J 0
(-12525 -2100);
DISPLAY 0.680851 (-12525 -2100);
PAINT MONO (-12525 -2100);
DISPLAY INVISIBLE (-12525 -2100);
FORCEPROP 2 LAST CDS_SEC 1
J 0
(-12525 -2100);
DISPLAY 1.021277 (-12525 -2100);
DISPLAY INVISIBLE (-12525 -2100);
FORCEADD Q_RES..1
(-12475 -2250);
FORCEPROP 1 LAST PART_NUMBER CS00002JB13
J 0
(-12600 -2400);
DISPLAY 0.510638 (-12600 -2400);
DISPLAY INVISIBLE (-12600 -2400);
FORCEPROP 1 LAST VALUE 0
J 2
(-12325 -2250);
DISPLAY 0.638298 (-12325 -2250);
FORCEPROP 1 LAST TOLERANCE 5%
J 0
(-12300 -2250);
DISPLAY 0.638298 (-12300 -2250);
FORCEPROP 1 LAST $LOCATION R340
J 0
(-12675 -2250);
DISPLAY 0.638298 (-12675 -2250);
FORCEPROP 1 LASTPIN (-12575 -2250) $PN 1
J 0
(-12563 -2238);
DISPLAY 0.787234 (-12563 -2238);
FORCEPROP 1 LASTPIN (-12375 -2250) $PN 2
J 0
(-12413 -2238);
DISPLAY 0.787234 (-12413 -2238);
FORCEPROP 1 LAST PATH I164
J 0
(-12525 -2100);
DISPLAY 0.978723 (-12525 -2100);
PAINT WHITE (-12525 -2100);
DISPLAY INVISIBLE (-12525 -2100);
FORCEPROP 1 LAST PACK_TYPE 0402LF
J 0
(-12225 -2250);
DISPLAY 0.638298 (-12225 -2250);
DISPLAY INVISIBLE (-12225 -2250);
FORCEPROP 2 LAST CDS_LIB pure_quanta
J 0
(-12475 -2250);
PAINT MONO (-12475 -2250);
DISPLAY INVISIBLE (-12475 -2250);
FORCEPROP 1 LAST MATERIAL CHIP
J 0
(-12475 -2400);
DISPLAY 0.978723 (-12475 -2400);
DISPLAY INVISIBLE (-12475 -2400);
FORCEPROP 1 LAST WATTAGE 1/16W
J 2
(-12500 -2400);
DISPLAY 0.978723 (-12500 -2400);
DISPLAY INVISIBLE (-12500 -2400);
FORCEPROP 2 LAST CDS_LOCATION R340
J 0
(-12525 -2050);
DISPLAY 1.021277 (-12525 -2050);
DISPLAY INVISIBLE (-12525 -2050);
FORCEPROP 2 LAST $SEC 1
J 0
(-12525 -2050);
DISPLAY 0.680851 (-12525 -2050);
PAINT MONO (-12525 -2050);
DISPLAY INVISIBLE (-12525 -2050);
FORCEPROP 2 LAST CDS_SEC 1
J 0
(-12525 -2050);
DISPLAY 1.021277 (-12525 -2050);
DISPLAY INVISIBLE (-12525 -2050);
FORCEADD OFFPAGE..1
(-13300 -2300);
FORCEPROP 2 LAST $XR0 45 
J 0
(-13551 -2300);
DISPLAY 0.638298 (-13551 -2300);
PAINT MONO (-13551 -2300);
FORCEPROP 2 LAST PATH I165
J 0
(-13550 -2250);
DISPLAY 1.021277 (-13550 -2250);
DISPLAY INVISIBLE (-13550 -2250);
FORCEPROP 1 LAST COMMENT_BODY TRUE
J 0
(-13175 -2400);
DISPLAY 0.872340 (-13175 -2400);
PAINT GREEN (-13175 -2400);
DISPLAY INVISIBLE (-13175 -2400);
FORCEPROP 1 LAST OFFPAGE TRUE
J 0
(-12975 -2425);
DISPLAY 0.872340 (-12975 -2425);
PAINT GREEN (-12975 -2425);
DISPLAY INVISIBLE (-12975 -2425);
FORCEPROP 2 LAST CDS_LIB standard
J 0
(-13300 -2300);
PAINT MONO (-13300 -2300);
DISPLAY INVISIBLE (-13300 -2300);
FORCEADD OFFPAGE..1
(-13300 -2250);
FORCEPROP 2 LAST $XR0 14 
J 0
(-13551 -2250);
DISPLAY 0.638298 (-13551 -2250);
PAINT MONO (-13551 -2250);
FORCEPROP 2 LAST PATH I166
J 0
(-13550 -2200);
DISPLAY 1.021277 (-13550 -2200);
DISPLAY INVISIBLE (-13550 -2200);
FORCEPROP 1 LAST COMMENT_BODY TRUE
J 0
(-13175 -2350);
DISPLAY 0.872340 (-13175 -2350);
PAINT GREEN (-13175 -2350);
DISPLAY INVISIBLE (-13175 -2350);
FORCEPROP 1 LAST OFFPAGE TRUE
J 0
(-12975 -2375);
DISPLAY 0.872340 (-12975 -2375);
PAINT GREEN (-12975 -2375);
DISPLAY INVISIBLE (-12975 -2375);
FORCEPROP 2 LAST CDS_LIB standard
J 0
(-13300 -2250);
PAINT MONO (-13300 -2250);
DISPLAY INVISIBLE (-13300 -2250);
FORCEADD OFFPAGE..1
(-13225 -3150);
FORCEPROP 2 LAST $XR0 45 
J 0
(-13446 -3150);
DISPLAY 0.638298 (-13446 -3150);
PAINT MONO (-13446 -3150);
FORCEPROP 2 LAST CDS_LIB standard
J 0
(-13225 -3150);
PAINT MONO (-13225 -3150);
DISPLAY INVISIBLE (-13225 -3150);
FORCEPROP 1 LAST OFFPAGE TRUE
J 0
(-12900 -3275);
DISPLAY 0.872340 (-12900 -3275);
PAINT GREEN (-12900 -3275);
DISPLAY INVISIBLE (-12900 -3275);
FORCEPROP 1 LAST COMMENT_BODY TRUE
J 0
(-13100 -3250);
DISPLAY 0.872340 (-13100 -3250);
PAINT GREEN (-13100 -3250);
DISPLAY INVISIBLE (-13100 -3250);
FORCEPROP 2 LAST PATH I167
J 0
(-13475 -3100);
DISPLAY 1.021277 (-13475 -3100);
DISPLAY INVISIBLE (-13475 -3100);
FORCEADD OFFPAGE..1
(-13225 -3100);
FORCEPROP 2 LAST $XR0 14 
J 0
(-13446 -3100);
DISPLAY 0.638298 (-13446 -3100);
PAINT MONO (-13446 -3100);
FORCEPROP 2 LAST CDS_LIB standard
J 0
(-13225 -3100);
PAINT MONO (-13225 -3100);
DISPLAY INVISIBLE (-13225 -3100);
FORCEPROP 1 LAST OFFPAGE TRUE
J 0
(-12900 -3225);
DISPLAY 0.872340 (-12900 -3225);
PAINT GREEN (-12900 -3225);
DISPLAY INVISIBLE (-12900 -3225);
FORCEPROP 1 LAST COMMENT_BODY TRUE
J 0
(-13100 -3200);
DISPLAY 0.872340 (-13100 -3200);
PAINT GREEN (-13100 -3200);
DISPLAY INVISIBLE (-13100 -3200);
FORCEPROP 2 LAST PATH I168
J 0
(-13475 -3050);
DISPLAY 1.021277 (-13475 -3050);
DISPLAY INVISIBLE (-13475 -3050);
FORCEADD Q_RES..2
(-12050 -1050);
FORCEPROP 1 LAST PART_NUMBER CS11502FB07
J 0
(-12010 -1175);
DISPLAY 0.638298 (-12010 -1175);
DISPLAY INVISIBLE (-12010 -1175);
FORCEPROP 1 LAST VALUE 150
J 0
(-12005 -975);
DISPLAY 0.638298 (-12005 -975);
FORCEPROP 1 LAST MATERIAL CHIP
J 0
(-12010 -1125);
DISPLAY 0.638298 (-12010 -1125);
FORCEPROP 1 LAST TOLERANCE 1%
J 0
(-12005 -1025);
DISPLAY 0.638298 (-12005 -1025);
FORCEPROP 1 LAST PACK_TYPE 0402LF
J 0
(-12010 -1225);
DISPLAY 0.638298 (-12010 -1225);
FORCEPROP 1 LAST WATTAGE 1/16W
J 0
(-12010 -1075);
DISPLAY 0.638298 (-12010 -1075);
FORCEPROP 1 LAST $LOCATION R4390
J 0
(-12005 -925);
DISPLAY 0.638298 (-12005 -925);
FORCEPROP 1 LASTPIN (-12050 -950) $PN 1
J 0
(-12045 -988);
DISPLAY 0.787234 (-12045 -988);
PAINT MONO (-12045 -988);
FORCEPROP 1 LASTPIN (-12050 -1150) $PN 2
J 0
(-12045 -1140);
DISPLAY 0.787234 (-12045 -1140);
PAINT MONO (-12045 -1140);
FORCEPROP 1 LAST PATH I169
J 0
(-12000 -875);
DISPLAY 0.978723 (-12000 -875);
PAINT WHITE (-12000 -875);
DISPLAY INVISIBLE (-12000 -875);
FORCEPROP 2 LAST CDS_LIB pure_quanta
J 0
(-12050 -1050);
DISPLAY INVISIBLE (-12050 -1050);
FORCEPROP 0 LAST CDS_LOCATION R4390
J 0
(-12000 -875);
DISPLAY 1.021277 (-12000 -875);
DISPLAY INVISIBLE (-12000 -875);
FORCEPROP 0 LAST $SEC 1
J 0
(-12000 -875);
DISPLAY 0.680851 (-12000 -875);
PAINT MONO (-12000 -875);
DISPLAY INVISIBLE (-12000 -875);
FORCEPROP 0 LAST CDS_SEC 1
J 0
(-12000 -875);
DISPLAY 1.021277 (-12000 -875);
DISPLAY INVISIBLE (-12000 -875);
FORCEADD Q_RES..1
(-11325 -3150);
FORCEPROP 1 LAST PART_NUMBER CS00002JB13
J 0
(-11450 -3300);
DISPLAY 0.510638 (-11450 -3300);
DISPLAY INVISIBLE (-11450 -3300);
FORCEPROP 1 LAST TOLERANCE 5%
J 0
(-11150 -3150);
DISPLAY 0.638298 (-11150 -3150);
FORCEPROP 1 LAST VALUE 0
J 2
(-11175 -3150);
DISPLAY 0.638298 (-11175 -3150);
FORCEPROP 1 LAST LOCATION R346
J 0
(-11525 -3150);
DISPLAY 0.638298 (-11525 -3150);
FORCEPROP 1 LASTPIN (-11425 -3150) $PN 1
J 0
(-11413 -3138);
DISPLAY 0.787234 (-11413 -3138);
PAINT MONO (-11413 -3138);
FORCEPROP 1 LASTPIN (-11225 -3150) $PN 2
J 0
(-11263 -3138);
DISPLAY 0.787234 (-11263 -3138);
PAINT MONO (-11263 -3138);
FORCEPROP 2 LAST CDS_LIB pure_quanta
J 0
(-11325 -3150);
DISPLAY INVISIBLE (-11325 -3150);
FORCEPROP 1 LAST WATTAGE 1/16W
J 2
(-11350 -3300);
DISPLAY 0.978723 (-11350 -3300);
DISPLAY INVISIBLE (-11350 -3300);
FORCEPROP 1 LAST MATERIAL CHIP
J 0
(-11325 -3300);
DISPLAY 0.978723 (-11325 -3300);
DISPLAY INVISIBLE (-11325 -3300);
FORCEPROP 1 LAST PACK_TYPE 0402LF
J 0
(-11075 -3150);
DISPLAY 0.638298 (-11075 -3150);
DISPLAY INVISIBLE (-11075 -3150);
FORCEPROP 1 LAST PATH I171
J 0
(-11375 -3000);
DISPLAY 0.978723 (-11375 -3000);
PAINT WHITE (-11375 -3000);
DISPLAY INVISIBLE (-11375 -3000);
FORCEPROP 0 LAST $SEC 1
J 0
(-11150 -3100);
DISPLAY 0.680851 (-11150 -3100);
PAINT MONO (-11150 -3100);
DISPLAY INVISIBLE (-11150 -3100);
FORCEPROP 0 LAST CDS_SEC 1
J 0
(-11150 -3100);
DISPLAY 1.021277 (-11150 -3100);
DISPLAY INVISIBLE (-11150 -3100);
FORCEADD Q_RES..1
(-11325 -2300);
FORCEPROP 1 LAST PART_NUMBER CS00002JB13
J 0
(-11450 -2450);
DISPLAY 0.510638 (-11450 -2450);
DISPLAY INVISIBLE (-11450 -2450);
FORCEPROP 1 LAST TOLERANCE 5%
J 0
(-11150 -2300);
DISPLAY 0.638298 (-11150 -2300);
FORCEPROP 1 LAST VALUE 0
J 2
(-11175 -2300);
DISPLAY 0.638298 (-11175 -2300);
FORCEPROP 1 LAST LOCATION R342
J 0
(-11525 -2300);
DISPLAY 0.638298 (-11525 -2300);
FORCEPROP 1 LASTPIN (-11425 -2300) $PN 1
J 0
(-11413 -2288);
DISPLAY 0.787234 (-11413 -2288);
PAINT MONO (-11413 -2288);
FORCEPROP 1 LASTPIN (-11225 -2300) $PN 2
J 0
(-11263 -2288);
DISPLAY 0.787234 (-11263 -2288);
PAINT MONO (-11263 -2288);
FORCEPROP 1 LAST PATH I172
J 0
(-11375 -2150);
DISPLAY 0.978723 (-11375 -2150);
PAINT WHITE (-11375 -2150);
DISPLAY INVISIBLE (-11375 -2150);
FORCEPROP 2 LAST CDS_LIB pure_quanta
J 0
(-11325 -2300);
DISPLAY INVISIBLE (-11325 -2300);
FORCEPROP 1 LAST PACK_TYPE 0402LF
J 0
(-11075 -2300);
DISPLAY 0.638298 (-11075 -2300);
DISPLAY INVISIBLE (-11075 -2300);
FORCEPROP 1 LAST MATERIAL CHIP
J 0
(-11325 -2450);
DISPLAY 0.978723 (-11325 -2450);
DISPLAY INVISIBLE (-11325 -2450);
FORCEPROP 1 LAST WATTAGE 1/16W
J 2
(-11350 -2450);
DISPLAY 0.978723 (-11350 -2450);
DISPLAY INVISIBLE (-11350 -2450);
FORCEPROP 0 LAST $SEC 1
J 0
(-11150 -2250);
DISPLAY 0.680851 (-11150 -2250);
PAINT MONO (-11150 -2250);
DISPLAY INVISIBLE (-11150 -2250);
FORCEPROP 0 LAST CDS_SEC 1
J 0
(-11150 -2250);
DISPLAY 1.021277 (-11150 -2250);
DISPLAY INVISIBLE (-11150 -2250);
FORCEADD Q_RES..1
(-11325 -1375);
FORCEPROP 1 LAST PART_NUMBER CS00002JB13
J 0
(-11450 -1525);
DISPLAY 0.510638 (-11450 -1525);
DISPLAY INVISIBLE (-11450 -1525);
FORCEPROP 1 LAST TOLERANCE 5%
J 0
(-11150 -1375);
DISPLAY 0.638298 (-11150 -1375);
FORCEPROP 1 LAST VALUE 0
J 2
(-11175 -1375);
DISPLAY 0.638298 (-11175 -1375);
FORCEPROP 1 LAST LOCATION R338
J 0
(-11525 -1375);
DISPLAY 0.638298 (-11525 -1375);
FORCEPROP 1 LASTPIN (-11425 -1375) $PN 1
J 0
(-11413 -1363);
DISPLAY 0.787234 (-11413 -1363);
PAINT MONO (-11413 -1363);
FORCEPROP 1 LASTPIN (-11225 -1375) $PN 2
J 0
(-11263 -1363);
DISPLAY 0.787234 (-11263 -1363);
PAINT MONO (-11263 -1363);
FORCEPROP 2 LAST CDS_LIB pure_quanta
J 0
(-11325 -1375);
DISPLAY INVISIBLE (-11325 -1375);
FORCEPROP 1 LAST WATTAGE 1/16W
J 2
(-11350 -1525);
DISPLAY 0.978723 (-11350 -1525);
DISPLAY INVISIBLE (-11350 -1525);
FORCEPROP 1 LAST MATERIAL CHIP
J 0
(-11325 -1525);
DISPLAY 0.978723 (-11325 -1525);
DISPLAY INVISIBLE (-11325 -1525);
FORCEPROP 1 LAST PACK_TYPE 0402LF
J 0
(-11075 -1375);
DISPLAY 0.638298 (-11075 -1375);
DISPLAY INVISIBLE (-11075 -1375);
FORCEPROP 1 LAST PATH I173
J 0
(-11375 -1225);
DISPLAY 0.978723 (-11375 -1225);
PAINT WHITE (-11375 -1225);
DISPLAY INVISIBLE (-11375 -1225);
FORCEPROP 0 LAST $SEC 1
J 0
(-11150 -1325);
DISPLAY 0.680851 (-11150 -1325);
PAINT MONO (-11150 -1325);
DISPLAY INVISIBLE (-11150 -1325);
FORCEPROP 0 LAST CDS_SEC 1
J 0
(-11150 -1325);
DISPLAY 1.021277 (-11150 -1325);
DISPLAY INVISIBLE (-11150 -1325);
FORCEADD Q_RES..2
(-12075 -1975);
FORCEPROP 1 LAST PART_NUMBER CS11502FB07
J 0
(-12035 -2100);
DISPLAY 0.638298 (-12035 -2100);
DISPLAY INVISIBLE (-12035 -2100);
FORCEPROP 1 LAST PACK_TYPE 0402LF
J 0
(-12035 -2150);
DISPLAY 0.638298 (-12035 -2150);
FORCEPROP 1 LAST TOLERANCE 1%
J 0
(-12030 -1950);
DISPLAY 0.638298 (-12030 -1950);
FORCEPROP 1 LAST WATTAGE 1/16W
J 0
(-12035 -2000);
DISPLAY 0.638298 (-12035 -2000);
FORCEPROP 1 LAST MATERIAL CHIP
J 0
(-12035 -2050);
DISPLAY 0.638298 (-12035 -2050);
FORCEPROP 1 LAST VALUE 150
J 0
(-12030 -1900);
DISPLAY 0.638298 (-12030 -1900);
FORCEPROP 1 LAST $LOCATION R4388
J 0
(-12030 -1850);
DISPLAY 0.638298 (-12030 -1850);
FORCEPROP 1 LASTPIN (-12075 -1875) $PN 1
J 0
(-12070 -1913);
DISPLAY 0.787234 (-12070 -1913);
PAINT MONO (-12070 -1913);
FORCEPROP 1 LASTPIN (-12075 -2075) $PN 2
J 0
(-12070 -2065);
DISPLAY 0.787234 (-12070 -2065);
PAINT MONO (-12070 -2065);
FORCEPROP 1 LAST PATH I174
J 0
(-12025 -1800);
DISPLAY 0.978723 (-12025 -1800);
PAINT WHITE (-12025 -1800);
DISPLAY INVISIBLE (-12025 -1800);
FORCEPROP 2 LAST CDS_LIB pure_quanta
J 0
(-12075 -1975);
DISPLAY INVISIBLE (-12075 -1975);
FORCEPROP 0 LAST CDS_LOCATION R4388
J 0
(-12025 -1800);
DISPLAY 1.021277 (-12025 -1800);
DISPLAY INVISIBLE (-12025 -1800);
FORCEPROP 0 LAST $SEC 1
J 0
(-12025 -1800);
DISPLAY 0.680851 (-12025 -1800);
PAINT MONO (-12025 -1800);
DISPLAY INVISIBLE (-12025 -1800);
FORCEPROP 0 LAST CDS_SEC 1
J 0
(-12025 -1800);
DISPLAY 1.021277 (-12025 -1800);
DISPLAY INVISIBLE (-12025 -1800);
FORCEADD UNIVERSAL_POWER..1
(-12075 -1775);
FORCEPROP 3 LASTPIN (-12075 -1825) SIG_NAME PVNN_TERM_CPU0\g
J 0
(-12065 -1815);
DISPLAY 0.659574 (-12065 -1815);
PAINT MONO (-12065 -1815);
DISPLAY INVISIBLE (-12065 -1815);
FORCEPROP 1 LAST HDL_POWER PVNN_TERM_CPU0
J 1
(-12075 -1725);
DISPLAY 0.872340 (-12075 -1725);
PAINT GREEN (-12075 -1725);
FORCEPROP 1 LAST PATH I175
J 0
(-12025 -1750);
DISPLAY 0.872340 (-12025 -1750);
PAINT AQUA (-12025 -1750);
DISPLAY INVISIBLE (-12025 -1750);
FORCEPROP 2 LAST CDS_LIB logical_power
J 0
(-12075 -1775);
DISPLAY INVISIBLE (-12075 -1775);
FORCEADD UNIVERSAL_POWER..1
(-12075 -2625);
FORCEPROP 3 LASTPIN (-12075 -2675) SIG_NAME PVNN_TERM_CPU0\g
J 0
(-12065 -2665);
DISPLAY 0.659574 (-12065 -2665);
PAINT MONO (-12065 -2665);
DISPLAY INVISIBLE (-12065 -2665);
FORCEPROP 1 LAST HDL_POWER PVNN_TERM_CPU0
J 1
(-12075 -2575);
DISPLAY 0.872340 (-12075 -2575);
PAINT GREEN (-12075 -2575);
FORCEPROP 1 LAST PATH I176
J 0
(-12025 -2600);
DISPLAY 0.872340 (-12025 -2600);
PAINT AQUA (-12025 -2600);
DISPLAY INVISIBLE (-12025 -2600);
FORCEPROP 2 LAST CDS_LIB logical_power
J 0
(-12075 -2625);
DISPLAY INVISIBLE (-12075 -2625);
FORCEADD Q_RES..2
(-12075 -2825);
FORCEPROP 1 LAST PART_NUMBER CS11502FB07
J 0
(-12035 -2950);
DISPLAY 0.638298 (-12035 -2950);
DISPLAY INVISIBLE (-12035 -2950);
FORCEPROP 1 LAST TOLERANCE 1%
J 0
(-12030 -2800);
DISPLAY 0.638298 (-12030 -2800);
FORCEPROP 1 LAST MATERIAL CHIP
J 0
(-12035 -2900);
DISPLAY 0.638298 (-12035 -2900);
FORCEPROP 1 LAST WATTAGE 1/16W
J 0
(-12035 -2850);
DISPLAY 0.638298 (-12035 -2850);
FORCEPROP 1 LAST PACK_TYPE 0402LF
J 0
(-12035 -3000);
DISPLAY 0.638298 (-12035 -3000);
FORCEPROP 1 LAST VALUE 150
J 0
(-12030 -2750);
DISPLAY 0.638298 (-12030 -2750);
FORCEPROP 1 LAST $LOCATION R4389
J 0
(-12030 -2700);
DISPLAY 0.638298 (-12030 -2700);
FORCEPROP 1 LASTPIN (-12075 -2725) $PN 1
J 0
(-12070 -2763);
DISPLAY 0.787234 (-12070 -2763);
PAINT MONO (-12070 -2763);
FORCEPROP 1 LASTPIN (-12075 -2925) $PN 2
J 0
(-12070 -2915);
DISPLAY 0.787234 (-12070 -2915);
PAINT MONO (-12070 -2915);
FORCEPROP 1 LAST PATH I177
J 0
(-12025 -2650);
DISPLAY 0.978723 (-12025 -2650);
PAINT WHITE (-12025 -2650);
DISPLAY INVISIBLE (-12025 -2650);
FORCEPROP 2 LAST CDS_LIB pure_quanta
J 0
(-12075 -2825);
DISPLAY INVISIBLE (-12075 -2825);
FORCEPROP 0 LAST CDS_LOCATION R4389
J 0
(-12025 -2650);
DISPLAY 1.021277 (-12025 -2650);
DISPLAY INVISIBLE (-12025 -2650);
FORCEPROP 0 LAST $SEC 1
J 0
(-12025 -2650);
DISPLAY 0.680851 (-12025 -2650);
PAINT MONO (-12025 -2650);
DISPLAY INVISIBLE (-12025 -2650);
FORCEPROP 0 LAST CDS_SEC 1
J 0
(-12025 -2650);
DISPLAY 1.021277 (-12025 -2650);
DISPLAY INVISIBLE (-12025 -2650);
FORCEADD OFFPAGE..2
(-4800 -2875);
FORCEPROP 2 LAST $XR1 182 
J 0
(-4491 -2875);
DISPLAY 0.638298 (-4491 -2875);
PAINT MONO (-4491 -2875);
FORCEPROP 2 LAST $XR0 204 
J 0
(-4611 -2875);
DISPLAY 0.638298 (-4611 -2875);
PAINT MONO (-4611 -2875);
FORCEPROP 2 LAST CDS_LIB standard
J 0
(-4800 -2875);
DISPLAY INVISIBLE (-4800 -2875);
FORCEPROP 1 LAST OFFPAGE TRUE
J 0
(-4475 -3000);
DISPLAY 0.872340 (-4475 -3000);
PAINT GREEN (-4475 -3000);
DISPLAY INVISIBLE (-4475 -3000);
FORCEPROP 1 LAST COMMENT_BODY TRUE
J 0
(-4845 -2970);
DISPLAY 0.872340 (-4845 -2970);
PAINT GREEN (-4845 -2970);
DISPLAY INVISIBLE (-4845 -2970);
FORCEPROP 2 LAST PATH I178
J 0
(-4475 -2825);
DISPLAY 1.021277 (-4475 -2825);
DISPLAY INVISIBLE (-4475 -2825);
FORCEADD OFFPAGE..2
(-4800 -2375);
FORCEPROP 2 LAST $XR1 182 
J 0
(-4491 -2375);
DISPLAY 0.638298 (-4491 -2375);
PAINT MONO (-4491 -2375);
FORCEPROP 2 LAST $XR0 204 
J 0
(-4611 -2375);
DISPLAY 0.638298 (-4611 -2375);
PAINT MONO (-4611 -2375);
FORCEPROP 2 LAST CDS_LIB standard
J 0
(-4800 -2375);
DISPLAY INVISIBLE (-4800 -2375);
FORCEPROP 1 LAST OFFPAGE TRUE
J 0
(-4475 -2500);
DISPLAY 0.872340 (-4475 -2500);
PAINT GREEN (-4475 -2500);
DISPLAY INVISIBLE (-4475 -2500);
FORCEPROP 1 LAST COMMENT_BODY TRUE
J 0
(-4845 -2470);
DISPLAY 0.872340 (-4845 -2470);
PAINT GREEN (-4845 -2470);
DISPLAY INVISIBLE (-4845 -2470);
FORCEPROP 2 LAST PATH I179
J 0
(-4475 -2325);
DISPLAY 1.021277 (-4475 -2325);
DISPLAY INVISIBLE (-4475 -2325);
FORCEADD OFFPAGE..2
(-4825 -1875);
FORCEPROP 2 LAST $XR1 182 
J 0
(-4516 -1875);
DISPLAY 0.638298 (-4516 -1875);
PAINT MONO (-4516 -1875);
FORCEPROP 2 LAST $XR0 204 
J 0
(-4636 -1875);
DISPLAY 0.638298 (-4636 -1875);
PAINT MONO (-4636 -1875);
FORCEPROP 2 LAST PATH I180
J 0
(-4500 -1825);
DISPLAY 1.021277 (-4500 -1825);
DISPLAY INVISIBLE (-4500 -1825);
FORCEPROP 2 LAST CDS_LIB standard
J 0
(-4825 -1875);
DISPLAY INVISIBLE (-4825 -1875);
FORCEPROP 1 LAST OFFPAGE TRUE
J 0
(-4500 -2000);
DISPLAY 0.872340 (-4500 -2000);
PAINT GREEN (-4500 -2000);
DISPLAY INVISIBLE (-4500 -2000);
FORCEPROP 1 LAST COMMENT_BODY TRUE
J 0
(-4870 -1970);
DISPLAY 0.872340 (-4870 -1970);
PAINT GREEN (-4870 -1970);
DISPLAY INVISIBLE (-4870 -1970);
FORCEADD Q_RES..2
(-7850 -1800);
FORCEPROP 1 LAST PART_NUMBER CS21002FB06
J 0
(-7810 -1925);
DISPLAY 0.638298 (-7810 -1925);
DISPLAY INVISIBLE (-7810 -1925);
FORCEPROP 1 LAST VALUE 1K
J 0
(-7805 -1725);
DISPLAY 0.638298 (-7805 -1725);
FORCEPROP 1 LAST TOLERANCE 1%
J 0
(-7805 -1775);
DISPLAY 0.638298 (-7805 -1775);
FORCEPROP 1 LAST WATTAGE 1/16W
J 0
(-7810 -1825);
DISPLAY 0.638298 (-7810 -1825);
FORCEPROP 1 LAST PACK_TYPE 0402LF
J 0
(-7810 -1975);
DISPLAY 0.638298 (-7810 -1975);
FORCEPROP 1 LAST MATERIAL CHIP
J 0
(-7810 -1875);
DISPLAY 0.638298 (-7810 -1875);
FORCEPROP 1 LAST LOCATION R4041
J 0
(-7805 -1675);
DISPLAY 0.638298 (-7805 -1675);
FORCEPROP 1 LASTPIN (-7850 -1700) $PN 1
J 0
(-7845 -1738);
DISPLAY 0.787234 (-7845 -1738);
PAINT MONO (-7845 -1738);
FORCEPROP 1 LASTPIN (-7850 -1900) $PN 2
J 0
(-7845 -1890);
DISPLAY 0.787234 (-7845 -1890);
PAINT MONO (-7845 -1890);
FORCEPROP 2 LAST CDS_LIB pure_quanta
J 0
(-7850 -1800);
DISPLAY INVISIBLE (-7850 -1800);
FORCEPROP 1 LAST PATH I181
J 0
(-7800 -1625);
DISPLAY 0.978723 (-7800 -1625);
PAINT WHITE (-7800 -1625);
DISPLAY INVISIBLE (-7800 -1625);
FORCEPROP 0 LAST $SEC 1
J 0
(-7800 -1625);
DISPLAY 0.680851 (-7800 -1625);
PAINT MONO (-7800 -1625);
DISPLAY INVISIBLE (-7800 -1625);
FORCEPROP 0 LAST CDS_SEC 1
J 0
(-7800 -1625);
DISPLAY 1.021277 (-7800 -1625);
DISPLAY INVISIBLE (-7800 -1625);
FORCEADD Q_RES..2
(-7850 -1425);
FORCEPROP 1 LAST PART_NUMBER CS24322FB03
J 0
(-7810 -1550);
DISPLAY 0.638298 (-7810 -1550);
DISPLAY INVISIBLE (-7810 -1550);
FORCEPROP 1 LAST MATERIAL CHIP
J 0
(-7810 -1500);
DISPLAY 0.638298 (-7810 -1500);
FORCEPROP 1 LAST PACK_TYPE 0402LF
J 0
(-7810 -1600);
DISPLAY 0.638298 (-7810 -1600);
FORCEPROP 1 LAST WATTAGE 1/16W
J 0
(-7810 -1450);
DISPLAY 0.638298 (-7810 -1450);
FORCEPROP 1 LAST TOLERANCE 1%
J 0
(-7805 -1400);
DISPLAY 0.638298 (-7805 -1400);
FORCEPROP 1 LAST VALUE 4.32K
J 0
(-7805 -1350);
DISPLAY 0.638298 (-7805 -1350);
FORCEPROP 1 LAST LOCATION R4038
J 0
(-7805 -1300);
DISPLAY 0.638298 (-7805 -1300);
FORCEPROP 1 LASTPIN (-7850 -1325) $PN 1
J 0
(-7845 -1363);
DISPLAY 0.787234 (-7845 -1363);
PAINT MONO (-7845 -1363);
FORCEPROP 1 LASTPIN (-7850 -1525) $PN 2
J 0
(-7845 -1515);
DISPLAY 0.787234 (-7845 -1515);
PAINT MONO (-7845 -1515);
FORCEPROP 1 LAST PATH I182
J 0
(-7800 -1250);
DISPLAY 0.978723 (-7800 -1250);
PAINT WHITE (-7800 -1250);
DISPLAY INVISIBLE (-7800 -1250);
FORCEPROP 2 LAST CDS_LIB pure_quanta
J 0
(-7850 -1425);
DISPLAY INVISIBLE (-7850 -1425);
FORCEPROP 0 LAST $SEC 1
J 0
(-7800 -1250);
DISPLAY 0.680851 (-7800 -1250);
PAINT MONO (-7800 -1250);
DISPLAY INVISIBLE (-7800 -1250);
FORCEPROP 0 LAST CDS_SEC 1
J 0
(-7800 -1250);
DISPLAY 1.021277 (-7800 -1250);
DISPLAY INVISIBLE (-7800 -1250);
FORCEADD Q_RES..1
(-5800 -1875);
FORCEPROP 1 LAST PART_NUMBER CS03322FB03
J 0
(-5925 -1975);
DISPLAY 0.510638 (-5925 -1975);
DISPLAY INVISIBLE (-5925 -1975);
FORCEPROP 1 LAST VALUE 33.2
J 2
(-5600 -1875);
DISPLAY 0.510638 (-5600 -1875);
FORCEPROP 1 LAST MATERIAL CHIP
J 0
(-5575 -1875);
DISPLAY 0.510638 (-5575 -1875);
FORCEPROP 1 LAST $LOCATION R4392
J 0
(-6000 -1875);
DISPLAY 0.638298 (-6000 -1875);
FORCEPROP 1 LASTPIN (-5900 -1875) $PN 1
J 0
(-5888 -1863);
DISPLAY 0.787234 (-5888 -1863);
PAINT MONO (-5888 -1863);
FORCEPROP 1 LASTPIN (-5700 -1875) $PN 2
J 0
(-5738 -1863);
DISPLAY 0.787234 (-5738 -1863);
PAINT MONO (-5738 -1863);
FORCEPROP 2 LAST CDS_LIB pure_quanta
J 0
(-5800 -1875);
DISPLAY INVISIBLE (-5800 -1875);
FORCEPROP 1 LAST PATH I183
J 0
(-5850 -1725);
DISPLAY 0.978723 (-5850 -1725);
PAINT WHITE (-5850 -1725);
DISPLAY INVISIBLE (-5850 -1725);
FORCEPROP 1 LAST PACK_TYPE 0402LF
J 0
(-5500 -1875);
DISPLAY 0.510638 (-5500 -1875);
DISPLAY INVISIBLE (-5500 -1875);
FORCEPROP 1 LAST TOLERANCE 1%
J 0
(-5575 -1875);
DISPLAY 0.510638 (-5575 -1875);
DISPLAY INVISIBLE (-5575 -1875);
FORCEPROP 1 LAST WATTAGE 1/16W
J 2
(-5650 -1925);
DISPLAY 0.510638 (-5650 -1925);
DISPLAY INVISIBLE (-5650 -1925);
FORCEPROP 0 LAST CDS_LOCATION R4392
J 0
(-5950 -1825);
DISPLAY 1.021277 (-5950 -1825);
DISPLAY INVISIBLE (-5950 -1825);
FORCEPROP 0 LAST $SEC 1
J 0
(-5950 -1825);
DISPLAY 0.680851 (-5950 -1825);
PAINT MONO (-5950 -1825);
DISPLAY INVISIBLE (-5950 -1825);
FORCEPROP 0 LAST CDS_SEC 1
J 0
(-5950 -1825);
DISPLAY 1.021277 (-5950 -1825);
DISPLAY INVISIBLE (-5950 -1825);
FORCEADD Q_RES..1
(-5800 -1800);
FORCEPROP 1 LAST PART_NUMBER CS03322FB03
J 0
(-5925 -1900);
DISPLAY 0.510638 (-5925 -1900);
DISPLAY INVISIBLE (-5925 -1900);
FORCEPROP 1 LAST VALUE 33.2
J 2
(-5600 -1800);
DISPLAY 0.510638 (-5600 -1800);
FORCEPROP 1 LAST MATERIAL CHIP
J 0
(-5575 -1800);
DISPLAY 0.510638 (-5575 -1800);
FORCEPROP 1 LAST $LOCATION R4050
J 0
(-6000 -1800);
DISPLAY 0.638298 (-6000 -1800);
FORCEPROP 1 LASTPIN (-5900 -1800) $PN 1
J 0
(-5888 -1788);
DISPLAY 0.787234 (-5888 -1788);
PAINT MONO (-5888 -1788);
FORCEPROP 1 LASTPIN (-5700 -1800) $PN 2
J 0
(-5738 -1788);
DISPLAY 0.787234 (-5738 -1788);
PAINT MONO (-5738 -1788);
FORCEPROP 1 LAST PACK_TYPE 0402LF
J 0
(-5500 -1800);
DISPLAY 0.510638 (-5500 -1800);
DISPLAY INVISIBLE (-5500 -1800);
FORCEPROP 1 LAST TOLERANCE 1%
J 0
(-5575 -1800);
DISPLAY 0.510638 (-5575 -1800);
DISPLAY INVISIBLE (-5575 -1800);
FORCEPROP 1 LAST WATTAGE 1/16W
J 2
(-5650 -1850);
DISPLAY 0.510638 (-5650 -1850);
DISPLAY INVISIBLE (-5650 -1850);
FORCEPROP 2 LAST CDS_LIB pure_quanta
J 0
(-5800 -1800);
DISPLAY INVISIBLE (-5800 -1800);
FORCEPROP 1 LAST PATH I184
J 0
(-5850 -1650);
DISPLAY 0.978723 (-5850 -1650);
PAINT WHITE (-5850 -1650);
DISPLAY INVISIBLE (-5850 -1650);
FORCEPROP 0 LAST CDS_LOCATION R4050
J 0
(-5975 -1750);
DISPLAY 1.021277 (-5975 -1750);
DISPLAY INVISIBLE (-5975 -1750);
FORCEPROP 0 LAST $SEC 1
J 0
(-5975 -1750);
DISPLAY 0.680851 (-5975 -1750);
PAINT MONO (-5975 -1750);
DISPLAY INVISIBLE (-5975 -1750);
FORCEPROP 0 LAST CDS_SEC 1
J 0
(-5975 -1750);
DISPLAY 1.021277 (-5975 -1750);
DISPLAY INVISIBLE (-5975 -1750);
FORCEADD OFFPAGE..2
(-4825 -1800);
FORCEPROP 2 LAST $XR0 216 
J 0
(-4636 -1800);
DISPLAY 0.638298 (-4636 -1800);
PAINT MONO (-4636 -1800);
FORCEPROP 1 LAST OFFPAGE TRUE
J 0
(-4500 -1925);
DISPLAY 0.872340 (-4500 -1925);
DISPLAY INVISIBLE (-4500 -1925);
FORCEPROP 1 LAST COMMENT_BODY TRUE
J 0
(-4870 -1895);
DISPLAY 0.872340 (-4870 -1895);
PAINT GREEN (-4870 -1895);
DISPLAY INVISIBLE (-4870 -1895);
FORCEPROP 2 LAST CDS_LIB standard
J 0
(-4825 -1800);
DISPLAY INVISIBLE (-4825 -1800);
FORCEPROP 2 LAST PATH I185
J 0
(-4625 -1750);
DISPLAY 1.021277 (-4625 -1750);
DISPLAY INVISIBLE (-4625 -1750);
FORCEADD OFFPAGE..2
(-4800 -2800);
FORCEPROP 2 LAST $XR0 216 
J 0
(-4611 -2800);
DISPLAY 0.638298 (-4611 -2800);
PAINT MONO (-4611 -2800);
FORCEPROP 1 LAST OFFPAGE TRUE
J 0
(-4475 -2925);
DISPLAY 0.872340 (-4475 -2925);
DISPLAY INVISIBLE (-4475 -2925);
FORCEPROP 1 LAST COMMENT_BODY TRUE
J 0
(-4845 -2895);
DISPLAY 0.872340 (-4845 -2895);
PAINT GREEN (-4845 -2895);
DISPLAY INVISIBLE (-4845 -2895);
FORCEPROP 2 LAST CDS_LIB standard
J 0
(-4800 -2800);
DISPLAY INVISIBLE (-4800 -2800);
FORCEPROP 2 LAST PATH I186
J 0
(-4600 -2750);
DISPLAY 1.021277 (-4600 -2750);
DISPLAY INVISIBLE (-4600 -2750);
FORCEADD Q_RES..1
(-5800 -2800);
FORCEPROP 1 LAST PART_NUMBER CS03322FB03
J 0
(-5925 -2900);
DISPLAY 0.510638 (-5925 -2900);
DISPLAY INVISIBLE (-5925 -2900);
FORCEPROP 1 LAST VALUE 33.2
J 2
(-5600 -2800);
DISPLAY 0.510638 (-5600 -2800);
FORCEPROP 1 LAST MATERIAL CHIP
J 0
(-5575 -2800);
DISPLAY 0.510638 (-5575 -2800);
FORCEPROP 1 LAST $LOCATION R4052
J 0
(-6000 -2800);
DISPLAY 0.638298 (-6000 -2800);
FORCEPROP 1 LASTPIN (-5900 -2800) $PN 1
J 0
(-5888 -2788);
DISPLAY 0.787234 (-5888 -2788);
PAINT MONO (-5888 -2788);
FORCEPROP 1 LASTPIN (-5700 -2800) $PN 2
J 0
(-5738 -2788);
DISPLAY 0.787234 (-5738 -2788);
PAINT MONO (-5738 -2788);
FORCEPROP 2 LAST CDS_LIB pure_quanta
J 0
(-5800 -2800);
DISPLAY INVISIBLE (-5800 -2800);
FORCEPROP 1 LAST PACK_TYPE 0402LF
J 0
(-5500 -2800);
DISPLAY 0.510638 (-5500 -2800);
DISPLAY INVISIBLE (-5500 -2800);
FORCEPROP 1 LAST TOLERANCE 1%
J 0
(-5575 -2800);
DISPLAY 0.510638 (-5575 -2800);
DISPLAY INVISIBLE (-5575 -2800);
FORCEPROP 1 LAST WATTAGE 1/16W
J 2
(-5650 -2850);
DISPLAY 0.510638 (-5650 -2850);
DISPLAY INVISIBLE (-5650 -2850);
FORCEPROP 1 LAST PATH I187
J 0
(-5850 -2650);
DISPLAY 0.978723 (-5850 -2650);
PAINT WHITE (-5850 -2650);
DISPLAY INVISIBLE (-5850 -2650);
FORCEPROP 0 LAST CDS_LOCATION R4052
J 0
(-5975 -2750);
DISPLAY 1.021277 (-5975 -2750);
DISPLAY INVISIBLE (-5975 -2750);
FORCEPROP 0 LAST $SEC 1
J 0
(-5975 -2750);
DISPLAY 0.680851 (-5975 -2750);
PAINT MONO (-5975 -2750);
DISPLAY INVISIBLE (-5975 -2750);
FORCEPROP 0 LAST CDS_SEC 1
J 0
(-5975 -2750);
DISPLAY 1.021277 (-5975 -2750);
DISPLAY INVISIBLE (-5975 -2750);
FORCEADD Q_RES..1
(-5800 -2375);
FORCEPROP 1 LAST PART_NUMBER CS03322FB03
J 0
(-5925 -2475);
DISPLAY 0.510638 (-5925 -2475);
DISPLAY INVISIBLE (-5925 -2475);
FORCEPROP 1 LAST MATERIAL CHIP
J 0
(-5575 -2375);
DISPLAY 0.510638 (-5575 -2375);
FORCEPROP 1 LAST VALUE 33.2
J 2
(-5600 -2375);
DISPLAY 0.510638 (-5600 -2375);
FORCEPROP 1 LAST $LOCATION R4393
J 0
(-6000 -2375);
DISPLAY 0.638298 (-6000 -2375);
FORCEPROP 1 LASTPIN (-5900 -2375) $PN 1
J 0
(-5888 -2363);
DISPLAY 0.787234 (-5888 -2363);
PAINT MONO (-5888 -2363);
FORCEPROP 1 LASTPIN (-5700 -2375) $PN 2
J 0
(-5738 -2363);
DISPLAY 0.787234 (-5738 -2363);
PAINT MONO (-5738 -2363);
FORCEPROP 1 LAST WATTAGE 1/16W
J 2
(-5650 -2425);
DISPLAY 0.510638 (-5650 -2425);
DISPLAY INVISIBLE (-5650 -2425);
FORCEPROP 1 LAST TOLERANCE 1%
J 0
(-5575 -2375);
DISPLAY 0.510638 (-5575 -2375);
DISPLAY INVISIBLE (-5575 -2375);
FORCEPROP 1 LAST PACK_TYPE 0402LF
J 0
(-5500 -2375);
DISPLAY 0.510638 (-5500 -2375);
DISPLAY INVISIBLE (-5500 -2375);
FORCEPROP 1 LAST PATH I188
J 0
(-5850 -2225);
DISPLAY 0.978723 (-5850 -2225);
PAINT WHITE (-5850 -2225);
DISPLAY INVISIBLE (-5850 -2225);
FORCEPROP 2 LAST CDS_LIB pure_quanta
J 0
(-5800 -2375);
DISPLAY INVISIBLE (-5800 -2375);
FORCEPROP 0 LAST CDS_LOCATION R4393
J 0
(-5975 -2325);
DISPLAY 1.021277 (-5975 -2325);
DISPLAY INVISIBLE (-5975 -2325);
FORCEPROP 0 LAST $SEC 1
J 0
(-5975 -2325);
DISPLAY 0.680851 (-5975 -2325);
PAINT MONO (-5975 -2325);
DISPLAY INVISIBLE (-5975 -2325);
FORCEPROP 0 LAST CDS_SEC 1
J 0
(-5975 -2325);
DISPLAY 1.021277 (-5975 -2325);
DISPLAY INVISIBLE (-5975 -2325);
FORCEADD Q_RES..1
(-5800 -2875);
FORCEPROP 1 LAST PART_NUMBER CS03322FB03
J 0
(-5925 -2975);
DISPLAY 0.510638 (-5925 -2975);
DISPLAY INVISIBLE (-5925 -2975);
FORCEPROP 1 LAST MATERIAL CHIP
J 0
(-5575 -2875);
DISPLAY 0.510638 (-5575 -2875);
FORCEPROP 1 LAST VALUE 33.2
J 2
(-5600 -2875);
DISPLAY 0.510638 (-5600 -2875);
FORCEPROP 1 LAST $LOCATION R4394
J 0
(-6000 -2875);
DISPLAY 0.638298 (-6000 -2875);
FORCEPROP 1 LASTPIN (-5900 -2875) $PN 1
J 0
(-5888 -2863);
DISPLAY 0.787234 (-5888 -2863);
PAINT MONO (-5888 -2863);
FORCEPROP 1 LASTPIN (-5700 -2875) $PN 2
J 0
(-5738 -2863);
DISPLAY 0.787234 (-5738 -2863);
PAINT MONO (-5738 -2863);
FORCEPROP 1 LAST PACK_TYPE 0402LF
J 0
(-5500 -2875);
DISPLAY 0.510638 (-5500 -2875);
DISPLAY INVISIBLE (-5500 -2875);
FORCEPROP 1 LAST TOLERANCE 1%
J 0
(-5575 -2875);
DISPLAY 0.510638 (-5575 -2875);
DISPLAY INVISIBLE (-5575 -2875);
FORCEPROP 1 LAST WATTAGE 1/16W
J 2
(-5650 -2925);
DISPLAY 0.510638 (-5650 -2925);
DISPLAY INVISIBLE (-5650 -2925);
FORCEPROP 1 LAST PATH I189
J 0
(-5850 -2725);
DISPLAY 0.978723 (-5850 -2725);
PAINT WHITE (-5850 -2725);
DISPLAY INVISIBLE (-5850 -2725);
FORCEPROP 2 LAST CDS_LIB pure_quanta
J 0
(-5800 -2875);
DISPLAY INVISIBLE (-5800 -2875);
FORCEPROP 0 LAST CDS_LOCATION R4394
J 0
(-5950 -2825);
DISPLAY 1.021277 (-5950 -2825);
DISPLAY INVISIBLE (-5950 -2825);
FORCEPROP 0 LAST $SEC 1
J 0
(-5950 -2825);
DISPLAY 0.680851 (-5950 -2825);
PAINT MONO (-5950 -2825);
DISPLAY INVISIBLE (-5950 -2825);
FORCEPROP 0 LAST CDS_SEC 1
J 0
(-5950 -2825);
DISPLAY 1.021277 (-5950 -2825);
DISPLAY INVISIBLE (-5950 -2825);
FORCEADD Q_RES..2
(-10425 -3025);
FORCEPROP 1 LAST PART_NUMBER CS11502FB07
J 0
(-10385 -3150);
DISPLAY 0.638298 (-10385 -3150);
DISPLAY INVISIBLE (-10385 -3150);
FORCEPROP 1 LAST MATERIAL CHIP
J 0
(-10385 -3100);
DISPLAY 0.638298 (-10385 -3100);
FORCEPROP 1 LAST WATTAGE 1/16W
J 0
(-10385 -3050);
DISPLAY 0.638298 (-10385 -3050);
FORCEPROP 1 LAST TOLERANCE 1%
J 0
(-10380 -3000);
DISPLAY 0.638298 (-10380 -3000);
FORCEPROP 1 LAST VALUE 150
J 0
(-10380 -2950);
DISPLAY 0.638298 (-10380 -2950);
FORCEPROP 1 LAST PACK_TYPE 0402LF
J 0
(-10385 -3200);
DISPLAY 0.638298 (-10385 -3200);
FORCEPROP 1 LAST $LOCATION R4391
J 0
(-10380 -2900);
DISPLAY 0.638298 (-10380 -2900);
FORCEPROP 1 LASTPIN (-10425 -2925) $PN 1
J 0
(-10420 -2963);
DISPLAY 0.787234 (-10420 -2963);
PAINT MONO (-10420 -2963);
FORCEPROP 1 LASTPIN (-10425 -3125) $PN 2
J 0
(-10420 -3115);
DISPLAY 0.787234 (-10420 -3115);
PAINT MONO (-10420 -3115);
FORCEPROP 1 LAST PATH I190
J 0
(-10375 -2850);
DISPLAY 0.978723 (-10375 -2850);
PAINT WHITE (-10375 -2850);
DISPLAY INVISIBLE (-10375 -2850);
FORCEPROP 2 LAST CDS_LIB pure_quanta
J 0
(-10425 -3025);
DISPLAY INVISIBLE (-10425 -3025);
FORCEPROP 0 LAST CDS_LOCATION R4391
J 0
(-10375 -2850);
DISPLAY 1.021277 (-10375 -2850);
DISPLAY INVISIBLE (-10375 -2850);
FORCEPROP 0 LAST $SEC 1
J 0
(-10375 -2850);
DISPLAY 0.680851 (-10375 -2850);
PAINT MONO (-10375 -2850);
DISPLAY INVISIBLE (-10375 -2850);
FORCEPROP 0 LAST CDS_SEC 1
J 0
(-10375 -2850);
DISPLAY 1.021277 (-10375 -2850);
DISPLAY INVISIBLE (-10375 -2850);
FORCEADD UNIVERSAL_GND..1
(-10425 -3250);
FORCEPROP 3 LASTPIN (-10425 -3200) SIG_NAME GND\g
J 0
(-10415 -3190);
DISPLAY 0.659574 (-10415 -3190);
PAINT MONO (-10415 -3190);
DISPLAY INVISIBLE (-10415 -3190);
FORCEPROP 1 LAST PATH I191
J 0
(-10350 -3250);
DISPLAY 0.872340 (-10350 -3250);
PAINT AQUA (-10350 -3250);
DISPLAY INVISIBLE (-10350 -3250);
FORCEPROP 1 LAST HDL_POWER GND
J 1
(-10400 -3325);
DISPLAY 0.872340 (-10400 -3325);
PAINT GREEN (-10400 -3325);
DISPLAY INVISIBLE (-10400 -3325);
FORCEPROP 2 LAST CDS_LIB logical_power
J 0
(-10425 -3250);
DISPLAY INVISIBLE (-10425 -3250);
FORCEADD UNIVERSAL_GND..1
R 2
(-7125 1800);
FORCEPROP 3 LASTPIN (-7125 1850) SIG_NAME GND\g
J 0
(-7115 1860);
DISPLAY 0.659574 (-7115 1860);
PAINT MONO (-7115 1860);
DISPLAY INVISIBLE (-7115 1860);
FORCEPROP 1 LAST PATH I20
J 2
(-7200 1800);
DISPLAY 0.872340 (-7200 1800);
PAINT AQUA (-7200 1800);
DISPLAY INVISIBLE (-7200 1800);
FORCEPROP 2 LAST CDS_LIB logical_power
R 3
J 0
(-7125 1800);
PAINT MONO (-7125 1800);
DISPLAY INVISIBLE (-7125 1800);
FORCEPROP 1 LAST HDL_POWER GND
J 1
(-7150 1725);
DISPLAY 0.872340 (-7150 1725);
PAINT GREEN (-7150 1725);
DISPLAY INVISIBLE (-7150 1725);
FORCEADD GTL2014PW..1
R 2
(-9475 1675);
FORCEPROP 1 LAST PART_NUMBER AL002014K01
J 2
(-9227 2080);
DISPLAY 0.723404 (-9227 2080);
PAINT GREEN (-9227 2080);
DISPLAY INVISIBLE (-9227 2080);
FORCEPROP 1 LAST MATERIAL IC
J 2
(-9227 2030);
DISPLAY 0.723404 (-9227 2030);
PAINT GREEN (-9227 2030);
FORCEPROP 2 LAST PART_TYPE SMLF
J 2
(-9250 2225);
DISPLAY 1.021277 (-9250 2225);
FORCEPROP 2 LAST VALUE GTL2014PW
J 2
(-9250 2175);
DISPLAY 1.021277 (-9250 2175);
FORCEPROP 1 LAST $LOCATION U304
J 2
(-9227 2125);
DISPLAY 0.680851 (-9227 2125);
PAINT GREEN (-9227 2125);
FORCEPROP 2 LASTPIN (-9075 1575) $PN 13
J 0
(-9065 1585);
DISPLAY 0.680851 (-9065 1585);
PAINT MONO (-9065 1585);
FORCEPROP 2 LASTPIN (-9075 1625) $PN 12
J 0
(-9065 1635);
DISPLAY 0.680851 (-9065 1635);
PAINT MONO (-9065 1635);
FORCEPROP 2 LASTPIN (-9075 1675) $PN 10
J 0
(-9065 1685);
DISPLAY 0.680851 (-9065 1685);
PAINT MONO (-9065 1685);
FORCEPROP 2 LASTPIN (-9075 1725) $PN 9
J 0
(-9065 1735);
DISPLAY 0.680851 (-9065 1735);
PAINT MONO (-9065 1735);
FORCEPROP 2 LASTPIN (-9875 1575) $PN 2
J 2
(-9885 1585);
DISPLAY 0.680851 (-9885 1585);
PAINT MONO (-9885 1585);
FORCEPROP 2 LASTPIN (-9875 1625) $PN 3
J 2
(-9885 1635);
DISPLAY 0.680851 (-9885 1635);
PAINT MONO (-9885 1635);
FORCEPROP 2 LASTPIN (-9875 1675) $PN 5
J 2
(-9885 1685);
DISPLAY 0.680851 (-9885 1685);
PAINT MONO (-9885 1685);
FORCEPROP 2 LASTPIN (-9875 1725) $PN 6
J 2
(-9885 1735);
DISPLAY 0.680851 (-9885 1735);
PAINT MONO (-9885 1735);
FORCEPROP 2 LASTPIN (-9075 1825) $PN 1
J 0
(-9065 1835);
DISPLAY 0.680851 (-9065 1835);
PAINT MONO (-9065 1835);
FORCEPROP 2 LASTPIN (-9875 1375) $PN 7
J 2
(-9885 1385);
DISPLAY 0.680851 (-9885 1385);
PAINT MONO (-9885 1385);
FORCEPROP 2 LASTPIN (-9875 1425) $PN 8
J 2
(-9885 1435);
DISPLAY 0.680851 (-9885 1435);
PAINT MONO (-9885 1435);
FORCEPROP 2 LASTPIN (-9875 1475) $PN 11
J 2
(-9885 1485);
DISPLAY 0.680851 (-9885 1485);
PAINT MONO (-9885 1485);
FORCEPROP 2 LASTPIN (-9075 1975) $PN 14
J 0
(-9065 1985);
DISPLAY 0.680851 (-9065 1985);
PAINT MONO (-9065 1985);
FORCEPROP 2 LASTPIN (-9075 1925) $PN 4
J 0
(-9065 1935);
DISPLAY 0.680851 (-9065 1935);
PAINT MONO (-9065 1935);
FORCEPROP 1 LAST PATH I27
J 2
(-9475 1675);
DISPLAY 0.723404 (-9475 1675);
PAINT GREEN (-9475 1675);
DISPLAY INVISIBLE (-9475 1675);
FORCEPROP 1 LAST NEEDS_NO_SIZE TRUE
J 2
(-9475 1675);
DISPLAY 0.723404 (-9475 1675);
PAINT GREEN (-9475 1675);
DISPLAY INVISIBLE (-9475 1675);
FORCEPROP 1 LAST CDS_LMAN_SYM_OUTLINE -250,350,250,-350
J 2
(-9475 1675);
DISPLAY 0.468085 (-9475 1675);
PAINT GREEN (-9475 1675);
DISPLAY INVISIBLE (-9475 1675);
FORCEPROP 2 LAST CDS_LIB pure_quanta
J 2
(-9475 1675);
PAINT RED (-9475 1675);
DISPLAY INVISIBLE (-9475 1675);
FORCEPROP 2 LAST SEC_TYPE 
J 2
(-9250 2275);
DISPLAY 1.021277 (-9250 2275);
DISPLAY INVISIBLE (-9250 2275);
FORCEPROP 2 LAST CDS_LOCATION U304
J 0
(-9250 2275);
DISPLAY 1.021277 (-9250 2275);
DISPLAY INVISIBLE (-9250 2275);
FORCEPROP 2 LAST SEC 1
J 2
(-9250 2275);
DISPLAY 0.680851 (-9250 2275);
PAINT MONO (-9250 2275);
DISPLAY INVISIBLE (-9250 2275);
FORCEADD OFFPAGE..1
(-10925 1575);
FORCEPROP 2 LAST $XR0 128 
J 0
(-11207 1575);
DISPLAY 0.638298 (-11207 1575);
PAINT MONO (-11207 1575);
FORCEPROP 2 LAST PATH I32
J 0
(-11200 1625);
DISPLAY 1.021277 (-11200 1625);
DISPLAY INVISIBLE (-11200 1625);
FORCEPROP 2 LAST CDS_LIB standard
J 2
(-10925 1575);
DISPLAY INVISIBLE (-10925 1575);
FORCEPROP 1 LAST COMMENT_BODY TRUE
J 0
(-10800 1475);
DISPLAY 1.170213 (-10800 1475);
PAINT GREEN (-10800 1475);
DISPLAY INVISIBLE (-10800 1475);
FORCEPROP 1 LAST OFFPAGE TRUE
J 0
(-10600 1450);
DISPLAY 1.170213 (-10600 1450);
PAINT GREEN (-10600 1450);
DISPLAY INVISIBLE (-10600 1450);
FORCEADD OFFPAGE..1
(-10925 1725);
FORCEPROP 2 LAST $XR0 128 
J 0
(-11207 1725);
DISPLAY 0.638298 (-11207 1725);
PAINT MONO (-11207 1725);
FORCEPROP 2 LAST PATH I33
J 0
(-11200 1775);
DISPLAY 1.021277 (-11200 1775);
DISPLAY INVISIBLE (-11200 1775);
FORCEPROP 2 LAST CDS_LIB standard
J 0
(-10925 1725);
DISPLAY INVISIBLE (-10925 1725);
FORCEPROP 1 LAST COMMENT_BODY TRUE
J 0
(-10800 1625);
DISPLAY 1.170213 (-10800 1625);
PAINT GREEN (-10800 1625);
DISPLAY INVISIBLE (-10800 1625);
FORCEPROP 1 LAST OFFPAGE TRUE
J 0
(-10600 1600);
DISPLAY 0.872340 (-10600 1600);
DISPLAY INVISIBLE (-10600 1600);
FORCEADD OFFPAGE..1
(-10925 1675);
FORCEPROP 2 LAST $XR0 128 
J 0
(-11207 1675);
DISPLAY 0.638298 (-11207 1675);
PAINT MONO (-11207 1675);
FORCEPROP 2 LAST PATH I34
J 0
(-11200 1725);
DISPLAY 1.021277 (-11200 1725);
DISPLAY INVISIBLE (-11200 1725);
FORCEPROP 1 LAST COMMENT_BODY TRUE
J 0
(-10800 1575);
DISPLAY 1.170213 (-10800 1575);
PAINT GREEN (-10800 1575);
DISPLAY INVISIBLE (-10800 1575);
FORCEPROP 1 LAST OFFPAGE TRUE
J 0
(-10600 1550);
DISPLAY 1.170213 (-10600 1550);
PAINT GREEN (-10600 1550);
DISPLAY INVISIBLE (-10600 1550);
FORCEPROP 2 LAST CDS_LIB standard
J 2
(-10925 1675);
PAINT MONO (-10925 1675);
DISPLAY INVISIBLE (-10925 1675);
FORCEADD OFFPAGE..1
(-10925 1625);
FORCEPROP 2 LAST $XR0 128 
J 0
(-11207 1625);
DISPLAY 0.638298 (-11207 1625);
PAINT MONO (-11207 1625);
FORCEPROP 2 LAST PATH I35
J 0
(-11200 1675);
DISPLAY 1.021277 (-11200 1675);
DISPLAY INVISIBLE (-11200 1675);
FORCEPROP 2 LAST CDS_LIB standard
J 0
(-10925 1625);
DISPLAY INVISIBLE (-10925 1625);
FORCEPROP 1 LAST OFFPAGE TRUE
J 0
(-10600 1500);
DISPLAY 0.872340 (-10600 1500);
DISPLAY INVISIBLE (-10600 1500);
FORCEPROP 1 LAST COMMENT_BODY TRUE
J 0
(-10800 1525);
DISPLAY 1.170213 (-10800 1525);
PAINT GREEN (-10800 1525);
DISPLAY INVISIBLE (-10800 1525);
FORCEADD Q_RES..1
(-7700 1575);
FORCEPROP 1 LAST PART_NUMBER CS03322FB03
J 0
(-7825 1475);
DISPLAY 0.510638 (-7825 1475);
DISPLAY INVISIBLE (-7825 1475);
FORCEPROP 1 LAST TOLERANCE 1%
J 0
(-7475 1575);
DISPLAY 0.510638 (-7475 1575);
FORCEPROP 1 LAST MATERIAL CHIP
J 0
(-7825 1525);
DISPLAY 0.510638 (-7825 1525);
FORCEPROP 1 LAST VALUE 33.2
J 2
(-7500 1575);
DISPLAY 0.510638 (-7500 1575);
FORCEPROP 1 LAST WATTAGE 1/16W
J 2
(-7550 1525);
DISPLAY 0.510638 (-7550 1525);
FORCEPROP 1 LAST PACK_TYPE 0402LF
J 0
(-7400 1575);
DISPLAY 0.510638 (-7400 1575);
FORCEPROP 1 LAST $LOCATION R4045
J 0
(-7875 1575);
DISPLAY 0.510638 (-7875 1575);
FORCEPROP 1 LASTPIN (-7800 1575) $PN 1
J 0
(-7788 1587);
DISPLAY 0.787234 (-7788 1587);
PAINT MONO (-7788 1587);
FORCEPROP 1 LASTPIN (-7600 1575) $PN 2
J 0
(-7638 1587);
DISPLAY 0.787234 (-7638 1587);
PAINT MONO (-7638 1587);
FORCEPROP 1 LAST PATH I36
J 0
(-7750 1725);
DISPLAY 0.978723 (-7750 1725);
PAINT WHITE (-7750 1725);
DISPLAY INVISIBLE (-7750 1725);
FORCEPROP 2 LAST CDS_LIB pure_quanta
J 0
(-7700 1575);
DISPLAY INVISIBLE (-7700 1575);
FORCEPROP 0 LAST CDS_LOCATION R4045
J 0
(-7875 1625);
DISPLAY 1.021277 (-7875 1625);
DISPLAY INVISIBLE (-7875 1625);
FORCEPROP 0 LAST $SEC 1
J 0
(-7875 1625);
DISPLAY 0.680851 (-7875 1625);
PAINT MONO (-7875 1625);
DISPLAY INVISIBLE (-7875 1625);
FORCEPROP 0 LAST CDS_SEC 1
J 0
(-7875 1625);
DISPLAY 1.021277 (-7875 1625);
DISPLAY INVISIBLE (-7875 1625);
FORCEADD Q_RES..1
(-7700 1625);
FORCEPROP 1 LAST PART_NUMBER CS03322FB03
J 0
(-7825 1525);
DISPLAY 0.510638 (-7825 1525);
DISPLAY INVISIBLE (-7825 1525);
FORCEPROP 1 LAST VALUE 33.2
J 2
(-7500 1625);
DISPLAY 0.510638 (-7500 1625);
FORCEPROP 1 LAST MATERIAL CHIP
J 0
(-7475 1625);
DISPLAY 0.510638 (-7475 1625);
FORCEPROP 1 LAST $LOCATION R4044
J 0
(-7875 1625);
DISPLAY 0.510638 (-7875 1625);
FORCEPROP 1 LASTPIN (-7800 1625) $PN 1
J 0
(-7788 1637);
DISPLAY 0.787234 (-7788 1637);
PAINT MONO (-7788 1637);
FORCEPROP 1 LASTPIN (-7600 1625) $PN 2
J 0
(-7638 1637);
DISPLAY 0.787234 (-7638 1637);
PAINT MONO (-7638 1637);
FORCEPROP 1 LAST PATH I37
J 0
(-7750 1775);
DISPLAY 0.978723 (-7750 1775);
PAINT WHITE (-7750 1775);
DISPLAY INVISIBLE (-7750 1775);
FORCEPROP 1 LAST WATTAGE 1/16W
J 2
(-7550 1575);
DISPLAY 0.510638 (-7550 1575);
DISPLAY INVISIBLE (-7550 1575);
FORCEPROP 1 LAST TOLERANCE 1%
J 0
(-7475 1625);
DISPLAY 0.510638 (-7475 1625);
DISPLAY INVISIBLE (-7475 1625);
FORCEPROP 1 LAST PACK_TYPE 0402LF
J 0
(-7400 1625);
DISPLAY 0.510638 (-7400 1625);
DISPLAY INVISIBLE (-7400 1625);
FORCEPROP 2 LAST CDS_LIB pure_quanta
J 0
(-7700 1625);
DISPLAY INVISIBLE (-7700 1625);
FORCEPROP 0 LAST CDS_LOCATION R4044
J 0
(-7875 1675);
DISPLAY 1.021277 (-7875 1675);
DISPLAY INVISIBLE (-7875 1675);
FORCEPROP 0 LAST $SEC 1
J 0
(-7875 1675);
DISPLAY 0.680851 (-7875 1675);
PAINT MONO (-7875 1675);
DISPLAY INVISIBLE (-7875 1675);
FORCEPROP 0 LAST CDS_SEC 1
J 0
(-7875 1675);
DISPLAY 1.021277 (-7875 1675);
DISPLAY INVISIBLE (-7875 1675);
FORCEADD Q_RES..1
(-7700 1675);
FORCEPROP 1 LAST PART_NUMBER CS03322FB03
J 0
(-7825 1575);
DISPLAY 0.510638 (-7825 1575);
DISPLAY INVISIBLE (-7825 1575);
FORCEPROP 1 LAST VALUE 33.2
J 2
(-7500 1675);
DISPLAY 0.510638 (-7500 1675);
FORCEPROP 1 LAST MATERIAL CHIP
J 0
(-7475 1675);
DISPLAY 0.510638 (-7475 1675);
FORCEPROP 1 LAST $LOCATION R4043
J 0
(-7875 1675);
DISPLAY 0.510638 (-7875 1675);
FORCEPROP 1 LASTPIN (-7800 1675) $PN 1
J 0
(-7788 1687);
DISPLAY 0.787234 (-7788 1687);
PAINT MONO (-7788 1687);
FORCEPROP 1 LASTPIN (-7600 1675) $PN 2
J 0
(-7638 1687);
DISPLAY 0.787234 (-7638 1687);
PAINT MONO (-7638 1687);
FORCEPROP 1 LAST PATH I38
J 0
(-7750 1825);
DISPLAY 0.978723 (-7750 1825);
PAINT WHITE (-7750 1825);
DISPLAY INVISIBLE (-7750 1825);
FORCEPROP 1 LAST WATTAGE 1/16W
J 2
(-7550 1625);
DISPLAY 0.510638 (-7550 1625);
DISPLAY INVISIBLE (-7550 1625);
FORCEPROP 1 LAST TOLERANCE 1%
J 0
(-7475 1675);
DISPLAY 0.510638 (-7475 1675);
DISPLAY INVISIBLE (-7475 1675);
FORCEPROP 1 LAST PACK_TYPE 0402LF
J 0
(-7400 1675);
DISPLAY 0.510638 (-7400 1675);
DISPLAY INVISIBLE (-7400 1675);
FORCEPROP 2 LAST CDS_LIB pure_quanta
J 0
(-7700 1675);
DISPLAY INVISIBLE (-7700 1675);
FORCEPROP 0 LAST CDS_LOCATION R4043
J 0
(-7875 1725);
DISPLAY 1.021277 (-7875 1725);
DISPLAY INVISIBLE (-7875 1725);
FORCEPROP 0 LAST $SEC 1
J 0
(-7875 1725);
DISPLAY 0.680851 (-7875 1725);
PAINT MONO (-7875 1725);
DISPLAY INVISIBLE (-7875 1725);
FORCEPROP 0 LAST CDS_SEC 1
J 0
(-7875 1725);
DISPLAY 1.021277 (-7875 1725);
DISPLAY INVISIBLE (-7875 1725);
FORCEADD Q_RES..1
(-7700 1725);
FORCEPROP 1 LAST PART_NUMBER CS03322FB03
J 0
(-7825 1625);
DISPLAY 0.510638 (-7825 1625);
DISPLAY INVISIBLE (-7825 1625);
FORCEPROP 1 LAST VALUE 33.2
J 2
(-7500 1725);
DISPLAY 0.510638 (-7500 1725);
FORCEPROP 1 LAST MATERIAL CHIP
J 0
(-7475 1725);
DISPLAY 0.510638 (-7475 1725);
FORCEPROP 1 LAST $LOCATION R4042
J 0
(-7875 1725);
DISPLAY 0.510638 (-7875 1725);
FORCEPROP 1 LASTPIN (-7800 1725) $PN 1
J 0
(-7788 1737);
DISPLAY 0.787234 (-7788 1737);
PAINT MONO (-7788 1737);
FORCEPROP 1 LASTPIN (-7600 1725) $PN 2
J 0
(-7638 1737);
DISPLAY 0.787234 (-7638 1737);
PAINT MONO (-7638 1737);
FORCEPROP 1 LAST PATH I39
J 0
(-7750 1875);
DISPLAY 0.978723 (-7750 1875);
PAINT WHITE (-7750 1875);
DISPLAY INVISIBLE (-7750 1875);
FORCEPROP 1 LAST PACK_TYPE 0402LF
J 0
(-7400 1725);
DISPLAY 0.510638 (-7400 1725);
DISPLAY INVISIBLE (-7400 1725);
FORCEPROP 1 LAST TOLERANCE 1%
J 0
(-7475 1725);
DISPLAY 0.510638 (-7475 1725);
DISPLAY INVISIBLE (-7475 1725);
FORCEPROP 1 LAST WATTAGE 1/16W
J 2
(-7550 1675);
DISPLAY 0.510638 (-7550 1675);
DISPLAY INVISIBLE (-7550 1675);
FORCEPROP 2 LAST CDS_LIB pure_quanta
J 0
(-7700 1725);
DISPLAY INVISIBLE (-7700 1725);
FORCEPROP 0 LAST CDS_LOCATION R4042
J 0
(-7875 1775);
DISPLAY 1.021277 (-7875 1775);
DISPLAY INVISIBLE (-7875 1775);
FORCEPROP 0 LAST $SEC 1
J 0
(-7875 1775);
DISPLAY 0.680851 (-7875 1775);
PAINT MONO (-7875 1775);
DISPLAY INVISIBLE (-7875 1775);
FORCEPROP 0 LAST CDS_SEC 1
J 0
(-7875 1775);
DISPLAY 1.021277 (-7875 1775);
DISPLAY INVISIBLE (-7875 1775);
FORCEADD GTL2014PW..1
R 2
(-9475 -400);
FORCEPROP 1 LAST PART_NUMBER AL002014K01
J 2
(-9227 5);
DISPLAY 0.723404 (-9227 5);
PAINT GREEN (-9227 5);
DISPLAY INVISIBLE (-9227 5);
FORCEPROP 1 LAST MATERIAL IC
J 2
(-9227 -45);
DISPLAY 0.723404 (-9227 -45);
PAINT GREEN (-9227 -45);
FORCEPROP 2 LAST VALUE GTL2014PW
J 2
(-9250 100);
DISPLAY 1.021277 (-9250 100);
FORCEPROP 2 LAST PART_TYPE SMLF
J 2
(-9250 150);
DISPLAY 1.021277 (-9250 150);
FORCEPROP 1 LAST $LOCATION U305
J 2
(-9227 50);
DISPLAY 0.680851 (-9227 50);
PAINT GREEN (-9227 50);
FORCEPROP 2 LASTPIN (-9075 -500) $PN 13
J 0
(-9065 -490);
DISPLAY 0.680851 (-9065 -490);
PAINT MONO (-9065 -490);
FORCEPROP 2 LASTPIN (-9075 -450) $PN 12
J 0
(-9065 -440);
DISPLAY 0.680851 (-9065 -440);
PAINT MONO (-9065 -440);
FORCEPROP 2 LASTPIN (-9075 -400) $PN 10
J 0
(-9065 -390);
DISPLAY 0.680851 (-9065 -390);
PAINT MONO (-9065 -390);
FORCEPROP 2 LASTPIN (-9075 -350) $PN 9
J 0
(-9065 -340);
DISPLAY 0.680851 (-9065 -340);
PAINT MONO (-9065 -340);
FORCEPROP 2 LASTPIN (-9875 -500) $PN 2
J 2
(-9885 -490);
DISPLAY 0.680851 (-9885 -490);
PAINT MONO (-9885 -490);
FORCEPROP 2 LASTPIN (-9875 -450) $PN 3
J 2
(-9885 -440);
DISPLAY 0.680851 (-9885 -440);
PAINT MONO (-9885 -440);
FORCEPROP 2 LASTPIN (-9875 -400) $PN 5
J 2
(-9885 -390);
DISPLAY 0.680851 (-9885 -390);
PAINT MONO (-9885 -390);
FORCEPROP 2 LASTPIN (-9875 -350) $PN 6
J 2
(-9885 -340);
DISPLAY 0.680851 (-9885 -340);
PAINT MONO (-9885 -340);
FORCEPROP 2 LASTPIN (-9075 -250) $PN 1
J 0
(-9065 -240);
DISPLAY 0.680851 (-9065 -240);
PAINT MONO (-9065 -240);
FORCEPROP 2 LASTPIN (-9875 -700) $PN 7
J 2
(-9885 -690);
DISPLAY 0.680851 (-9885 -690);
PAINT MONO (-9885 -690);
FORCEPROP 2 LASTPIN (-9875 -650) $PN 8
J 2
(-9885 -640);
DISPLAY 0.680851 (-9885 -640);
PAINT MONO (-9885 -640);
FORCEPROP 2 LASTPIN (-9875 -600) $PN 11
J 2
(-9885 -590);
DISPLAY 0.680851 (-9885 -590);
PAINT MONO (-9885 -590);
FORCEPROP 2 LASTPIN (-9075 -100) $PN 14
J 0
(-9065 -90);
DISPLAY 0.680851 (-9065 -90);
PAINT MONO (-9065 -90);
FORCEPROP 2 LASTPIN (-9075 -150) $PN 4
J 0
(-9065 -140);
DISPLAY 0.680851 (-9065 -140);
PAINT MONO (-9065 -140);
FORCEPROP 2 LAST SEC_TYPE 
J 2
(-9250 200);
DISPLAY 1.021277 (-9250 200);
DISPLAY INVISIBLE (-9250 200);
FORCEPROP 2 LAST CDS_LIB pure_quanta
J 2
(-9475 -400);
PAINT RED (-9475 -400);
DISPLAY INVISIBLE (-9475 -400);
FORCEPROP 1 LAST CDS_LMAN_SYM_OUTLINE -250,350,250,-350
J 2
(-9475 -400);
DISPLAY 0.468085 (-9475 -400);
PAINT GREEN (-9475 -400);
DISPLAY INVISIBLE (-9475 -400);
FORCEPROP 1 LAST NEEDS_NO_SIZE TRUE
J 2
(-9475 -400);
DISPLAY 0.723404 (-9475 -400);
PAINT GREEN (-9475 -400);
DISPLAY INVISIBLE (-9475 -400);
FORCEPROP 1 LAST PATH I44
J 2
(-9475 -400);
DISPLAY 0.723404 (-9475 -400);
PAINT GREEN (-9475 -400);
DISPLAY INVISIBLE (-9475 -400);
FORCEPROP 2 LAST CDS_LOCATION U305
J 0
(-9250 200);
DISPLAY 1.021277 (-9250 200);
DISPLAY INVISIBLE (-9250 200);
FORCEPROP 2 LAST SEC 1
J 2
(-9250 200);
DISPLAY 0.680851 (-9250 200);
PAINT MONO (-9250 200);
DISPLAY INVISIBLE (-9250 200);
FORCEADD UNIVERSAL_GND..1
R 2
(-7125 -275);
FORCEPROP 3 LASTPIN (-7125 -225) SIG_NAME GND\g
J 0
(-7115 -215);
DISPLAY 0.659574 (-7115 -215);
PAINT MONO (-7115 -215);
DISPLAY INVISIBLE (-7115 -215);
FORCEPROP 1 LAST PATH I49
J 2
(-7200 -275);
DISPLAY 0.872340 (-7200 -275);
PAINT AQUA (-7200 -275);
DISPLAY INVISIBLE (-7200 -275);
FORCEPROP 2 LAST CDS_LIB logical_power
R 3
J 0
(-7125 -275);
PAINT MONO (-7125 -275);
DISPLAY INVISIBLE (-7125 -275);
FORCEPROP 1 LAST HDL_POWER GND
J 1
(-7150 -350);
DISPLAY 0.872340 (-7150 -350);
PAINT GREEN (-7150 -350);
DISPLAY INVISIBLE (-7150 -350);
FORCEADD Q_RES..1
(-7700 -350);
FORCEPROP 1 LAST PART_NUMBER CS03322FB03
J 0
(-7825 -450);
DISPLAY 0.510638 (-7825 -450);
DISPLAY INVISIBLE (-7825 -450);
FORCEPROP 1 LAST MATERIAL CHIP
J 0
(-7475 -350);
DISPLAY 0.510638 (-7475 -350);
FORCEPROP 1 LAST VALUE 33.2
J 2
(-7500 -350);
DISPLAY 0.510638 (-7500 -350);
FORCEPROP 1 LAST $LOCATION R4046
J 0
(-7875 -350);
DISPLAY 0.510638 (-7875 -350);
FORCEPROP 1 LASTPIN (-7800 -350) $PN 1
J 0
(-7788 -338);
DISPLAY 0.787234 (-7788 -338);
PAINT MONO (-7788 -338);
FORCEPROP 1 LASTPIN (-7600 -350) $PN 2
J 0
(-7638 -338);
DISPLAY 0.787234 (-7638 -338);
PAINT MONO (-7638 -338);
FORCEPROP 1 LAST PATH I52
J 0
(-7750 -200);
DISPLAY 0.978723 (-7750 -200);
PAINT WHITE (-7750 -200);
DISPLAY INVISIBLE (-7750 -200);
FORCEPROP 1 LAST PACK_TYPE 0402LF
J 0
(-7400 -350);
DISPLAY 0.510638 (-7400 -350);
DISPLAY INVISIBLE (-7400 -350);
FORCEPROP 1 LAST TOLERANCE 1%
J 0
(-7475 -350);
DISPLAY 0.510638 (-7475 -350);
DISPLAY INVISIBLE (-7475 -350);
FORCEPROP 1 LAST WATTAGE 1/16W
J 2
(-7550 -400);
DISPLAY 0.510638 (-7550 -400);
DISPLAY INVISIBLE (-7550 -400);
FORCEPROP 2 LAST CDS_LIB pure_quanta
J 0
(-7700 -350);
DISPLAY INVISIBLE (-7700 -350);
FORCEPROP 0 LAST CDS_LOCATION R4046
J 0
(-7875 -300);
DISPLAY 1.021277 (-7875 -300);
DISPLAY INVISIBLE (-7875 -300);
FORCEPROP 0 LAST $SEC 1
J 0
(-7875 -300);
DISPLAY 0.680851 (-7875 -300);
PAINT MONO (-7875 -300);
DISPLAY INVISIBLE (-7875 -300);
FORCEPROP 0 LAST CDS_SEC 1
J 0
(-7875 -300);
DISPLAY 1.021277 (-7875 -300);
DISPLAY INVISIBLE (-7875 -300);
FORCEADD Q_RES..1
(-7700 -400);
FORCEPROP 1 LAST PART_NUMBER CS03322FB03
J 0
(-7825 -500);
DISPLAY 0.510638 (-7825 -500);
DISPLAY INVISIBLE (-7825 -500);
FORCEPROP 1 LAST VALUE 33.2
J 2
(-7500 -400);
DISPLAY 0.510638 (-7500 -400);
FORCEPROP 1 LAST MATERIAL CHIP
J 0
(-7475 -400);
DISPLAY 0.510638 (-7475 -400);
FORCEPROP 1 LAST $LOCATION R4047
J 0
(-7875 -400);
DISPLAY 0.510638 (-7875 -400);
FORCEPROP 1 LASTPIN (-7800 -400) $PN 1
J 0
(-7788 -388);
DISPLAY 0.787234 (-7788 -388);
PAINT MONO (-7788 -388);
FORCEPROP 1 LASTPIN (-7600 -400) $PN 2
J 0
(-7638 -388);
DISPLAY 0.787234 (-7638 -388);
PAINT MONO (-7638 -388);
FORCEPROP 1 LAST PATH I53
J 0
(-7750 -250);
DISPLAY 0.978723 (-7750 -250);
PAINT WHITE (-7750 -250);
DISPLAY INVISIBLE (-7750 -250);
FORCEPROP 1 LAST WATTAGE 1/16W
J 2
(-7550 -450);
DISPLAY 0.510638 (-7550 -450);
DISPLAY INVISIBLE (-7550 -450);
FORCEPROP 1 LAST TOLERANCE 1%
J 0
(-7475 -400);
DISPLAY 0.510638 (-7475 -400);
DISPLAY INVISIBLE (-7475 -400);
FORCEPROP 1 LAST PACK_TYPE 0402LF
J 0
(-7400 -400);
DISPLAY 0.510638 (-7400 -400);
DISPLAY INVISIBLE (-7400 -400);
FORCEPROP 2 LAST CDS_LIB pure_quanta
J 0
(-7700 -400);
DISPLAY INVISIBLE (-7700 -400);
FORCEPROP 0 LAST CDS_LOCATION R4047
J 0
(-7875 -350);
DISPLAY 1.021277 (-7875 -350);
DISPLAY INVISIBLE (-7875 -350);
FORCEPROP 0 LAST $SEC 1
J 0
(-7875 -350);
DISPLAY 0.680851 (-7875 -350);
PAINT MONO (-7875 -350);
DISPLAY INVISIBLE (-7875 -350);
FORCEPROP 0 LAST CDS_SEC 1
J 0
(-7875 -350);
DISPLAY 1.021277 (-7875 -350);
DISPLAY INVISIBLE (-7875 -350);
FORCEADD Q_RES..1
(-7700 -500);
FORCEPROP 1 LAST PART_NUMBER CS03322FB03
J 0
(-7825 -600);
DISPLAY 0.510638 (-7825 -600);
DISPLAY INVISIBLE (-7825 -600);
FORCEPROP 1 LAST MATERIAL CHIP
J 0
(-7825 -550);
DISPLAY 0.510638 (-7825 -550);
FORCEPROP 1 LAST TOLERANCE 1%
J 0
(-7475 -500);
DISPLAY 0.510638 (-7475 -500);
FORCEPROP 1 LAST VALUE 33.2
J 2
(-7500 -500);
DISPLAY 0.510638 (-7500 -500);
FORCEPROP 1 LAST PACK_TYPE 0402LF
J 0
(-7400 -500);
DISPLAY 0.510638 (-7400 -500);
FORCEPROP 1 LAST WATTAGE 1/16W
J 2
(-7550 -550);
DISPLAY 0.510638 (-7550 -550);
FORCEPROP 1 LAST $LOCATION R4049
J 0
(-7875 -500);
DISPLAY 0.510638 (-7875 -500);
FORCEPROP 1 LASTPIN (-7800 -500) $PN 1
J 0
(-7788 -488);
DISPLAY 0.787234 (-7788 -488);
PAINT MONO (-7788 -488);
FORCEPROP 1 LASTPIN (-7600 -500) $PN 2
J 0
(-7638 -488);
DISPLAY 0.787234 (-7638 -488);
PAINT MONO (-7638 -488);
FORCEPROP 1 LAST PATH I54
J 0
(-7750 -350);
DISPLAY 0.978723 (-7750 -350);
PAINT WHITE (-7750 -350);
DISPLAY INVISIBLE (-7750 -350);
FORCEPROP 2 LAST CDS_LIB pure_quanta
J 0
(-7700 -500);
DISPLAY INVISIBLE (-7700 -500);
FORCEPROP 0 LAST CDS_LOCATION R4049
J 0
(-7875 -450);
DISPLAY 1.021277 (-7875 -450);
DISPLAY INVISIBLE (-7875 -450);
FORCEPROP 0 LAST $SEC 1
J 0
(-7875 -450);
DISPLAY 0.680851 (-7875 -450);
PAINT MONO (-7875 -450);
DISPLAY INVISIBLE (-7875 -450);
FORCEPROP 0 LAST CDS_SEC 1
J 0
(-7875 -450);
DISPLAY 1.021277 (-7875 -450);
DISPLAY INVISIBLE (-7875 -450);
FORCEADD Q_RES..1
(-7700 -450);
FORCEPROP 1 LAST PART_NUMBER CS03322FB03
J 0
(-7825 -550);
DISPLAY 0.510638 (-7825 -550);
DISPLAY INVISIBLE (-7825 -550);
FORCEPROP 1 LAST VALUE 33.2
J 2
(-7500 -450);
DISPLAY 0.510638 (-7500 -450);
FORCEPROP 1 LAST MATERIAL CHIP
J 0
(-7475 -450);
DISPLAY 0.510638 (-7475 -450);
FORCEPROP 1 LAST $LOCATION R4048
J 0
(-7875 -450);
DISPLAY 0.510638 (-7875 -450);
FORCEPROP 1 LASTPIN (-7800 -450) $PN 1
J 0
(-7788 -438);
DISPLAY 0.787234 (-7788 -438);
PAINT MONO (-7788 -438);
FORCEPROP 1 LASTPIN (-7600 -450) $PN 2
J 0
(-7638 -438);
DISPLAY 0.787234 (-7638 -438);
PAINT MONO (-7638 -438);
FORCEPROP 1 LAST PATH I55
J 0
(-7750 -300);
DISPLAY 0.978723 (-7750 -300);
PAINT WHITE (-7750 -300);
DISPLAY INVISIBLE (-7750 -300);
FORCEPROP 1 LAST WATTAGE 1/16W
J 2
(-7550 -500);
DISPLAY 0.510638 (-7550 -500);
DISPLAY INVISIBLE (-7550 -500);
FORCEPROP 1 LAST TOLERANCE 1%
J 0
(-7475 -450);
DISPLAY 0.510638 (-7475 -450);
DISPLAY INVISIBLE (-7475 -450);
FORCEPROP 1 LAST PACK_TYPE 0402LF
J 0
(-7400 -450);
DISPLAY 0.510638 (-7400 -450);
DISPLAY INVISIBLE (-7400 -450);
FORCEPROP 2 LAST CDS_LIB pure_quanta
J 0
(-7700 -450);
DISPLAY INVISIBLE (-7700 -450);
FORCEPROP 0 LAST CDS_LOCATION R4048
J 0
(-7875 -400);
DISPLAY 1.021277 (-7875 -400);
DISPLAY INVISIBLE (-7875 -400);
FORCEPROP 0 LAST $SEC 1
J 0
(-7875 -400);
DISPLAY 0.680851 (-7875 -400);
PAINT MONO (-7875 -400);
DISPLAY INVISIBLE (-7875 -400);
FORCEPROP 0 LAST CDS_SEC 1
J 0
(-7875 -400);
DISPLAY 1.021277 (-7875 -400);
DISPLAY INVISIBLE (-7875 -400);
FORCEADD UNIVERSAL_GND..1
(-8825 0);
FORCEPROP 3 LASTPIN (-8825 50) SIG_NAME GND\g
J 0
(-8815 60);
DISPLAY 0.659574 (-8815 60);
PAINT MONO (-8815 60);
DISPLAY INVISIBLE (-8815 60);
FORCEPROP 1 LAST PATH I58
J 0
(-8750 0);
DISPLAY 0.872340 (-8750 0);
PAINT AQUA (-8750 0);
DISPLAY INVISIBLE (-8750 0);
FORCEPROP 2 LAST CDS_LIB logical_power
J 0
(-8825 0);
DISPLAY INVISIBLE (-8825 0);
FORCEPROP 1 LAST HDL_POWER GND
J 1
(-8800 -75);
DISPLAY 0.872340 (-8800 -75);
PAINT GREEN (-8800 -75);
DISPLAY INVISIBLE (-8800 -75);
FORCEADD Q_CAP..1
(-8825 225);
FORCEPROP 1 LAST PART_NUMBER CH5104KEB02
J 0
(-8775 75);
DISPLAY 0.404255 (-8775 75);
DISPLAY INVISIBLE (-8775 75);
FORCEPROP 1 LAST TOLERANCE 10%
J 0
(-8775 175);
DISPLAY 0.510638 (-8775 175);
FORCEPROP 1 LAST VALUE 1UF
J 0
(-8775 275);
DISPLAY 0.510638 (-8775 275);
FORCEPROP 1 LAST VOLTAGE 25V
J 0
(-8775 225);
DISPLAY 0.510638 (-8775 225);
FORCEPROP 1 LAST PACK_TYPE C0402
J 0
(-8775 25);
DISPLAY 0.510638 (-8775 25);
FORCEPROP 1 LAST MATERIAL X6S
J 0
(-8775 125);
DISPLAY 0.510638 (-8775 125);
FORCEPROP 1 LAST $LOCATION C2247
J 0
(-8775 325);
DISPLAY 0.638298 (-8775 325);
FORCEPROP 1 LASTPIN (-8825 325) $PN 1
J 0
(-8815 305);
DISPLAY 0.787234 (-8815 305);
FORCEPROP 1 LASTPIN (-8825 125) $PN 2
J 0
(-8815 105);
DISPLAY 0.787234 (-8815 105);
FORCEPROP 1 LAST PATH I59
J 0
(-8775 375);
DISPLAY 0.978723 (-8775 375);
PAINT WHITE (-8775 375);
DISPLAY INVISIBLE (-8775 375);
FORCEPROP 2 LAST CDS_LIB pure_quanta
J 0
(-8825 225);
DISPLAY INVISIBLE (-8825 225);
FORCEPROP 2 LAST CDS_LOCATION C2247
J 0
(-8775 425);
DISPLAY 1.021277 (-8775 425);
DISPLAY INVISIBLE (-8775 425);
FORCEPROP 2 LAST $SEC 1
J 0
(-8775 425);
DISPLAY 0.680851 (-8775 425);
PAINT MONO (-8775 425);
DISPLAY INVISIBLE (-8775 425);
FORCEPROP 2 LAST CDS_SEC 1
J 0
(-8775 425);
DISPLAY 0.680851 (-8775 425);
DISPLAY INVISIBLE (-8775 425);
FORCEADD UNIVERSAL_POWER..1
(-8975 475);
FORCEPROP 3 LASTPIN (-8975 425) SIG_NAME P3V3_AUX\g
J 0
(-8965 435);
DISPLAY 0.659574 (-8965 435);
PAINT MONO (-8965 435);
DISPLAY INVISIBLE (-8965 435);
FORCEPROP 1 LAST HDL_POWER P3V3_AUX
J 1
(-8975 525);
DISPLAY 0.872340 (-8975 525);
PAINT GREEN (-8975 525);
FORCEPROP 1 LAST PATH I60
J 0
(-8925 500);
DISPLAY 0.872340 (-8925 500);
PAINT AQUA (-8925 500);
DISPLAY INVISIBLE (-8925 500);
FORCEPROP 2 LAST CDS_LIB logical_power
J 0
(-8975 475);
PAINT RED (-8975 475);
DISPLAY INVISIBLE (-8975 475);
FORCEADD UNIVERSAL_GND..1
(-10000 -800);
FORCEPROP 3 LASTPIN (-10000 -750) SIG_NAME GND\g
J 0
(-9990 -740);
DISPLAY 0.659574 (-9990 -740);
PAINT MONO (-9990 -740);
DISPLAY INVISIBLE (-9990 -740);
FORCEPROP 1 LAST PATH I61
J 0
(-9925 -800);
DISPLAY 0.872340 (-9925 -800);
PAINT AQUA (-9925 -800);
DISPLAY INVISIBLE (-9925 -800);
FORCEPROP 1 LAST HDL_POWER GND
J 1
(-9975 -875);
DISPLAY 0.872340 (-9975 -875);
PAINT GREEN (-9975 -875);
DISPLAY INVISIBLE (-9975 -875);
FORCEPROP 2 LAST CDS_LIB logical_power
J 0
(-10000 -800);
DISPLAY INVISIBLE (-10000 -800);
FORCEADD OFFPAGE..1
(-10925 -350);
FORCEPROP 2 LAST $XR0 128 
J 0
(-11207 -350);
DISPLAY 0.638298 (-11207 -350);
PAINT MONO (-11207 -350);
FORCEPROP 2 LAST PATH I62
J 0
(-11200 -300);
DISPLAY 1.021277 (-11200 -300);
DISPLAY INVISIBLE (-11200 -300);
FORCEPROP 2 LAST CDS_LIB standard
J 0
(-10925 -350);
DISPLAY INVISIBLE (-10925 -350);
FORCEPROP 1 LAST OFFPAGE TRUE
J 0
(-10600 -475);
DISPLAY 0.872340 (-10600 -475);
DISPLAY INVISIBLE (-10600 -475);
FORCEPROP 1 LAST COMMENT_BODY TRUE
J 0
(-10800 -450);
DISPLAY 1.170213 (-10800 -450);
PAINT GREEN (-10800 -450);
DISPLAY INVISIBLE (-10800 -450);
FORCEADD OFFPAGE..1
(-10925 -400);
FORCEPROP 2 LAST $XR0 128 
J 0
(-11207 -400);
DISPLAY 0.638298 (-11207 -400);
PAINT MONO (-11207 -400);
FORCEPROP 2 LAST PATH I63
J 0
(-11200 -350);
DISPLAY 1.021277 (-11200 -350);
DISPLAY INVISIBLE (-11200 -350);
FORCEPROP 1 LAST COMMENT_BODY TRUE
J 0
(-10800 -500);
DISPLAY 1.170213 (-10800 -500);
PAINT GREEN (-10800 -500);
DISPLAY INVISIBLE (-10800 -500);
FORCEPROP 1 LAST OFFPAGE TRUE
J 0
(-10600 -525);
DISPLAY 1.170213 (-10600 -525);
PAINT GREEN (-10600 -525);
DISPLAY INVISIBLE (-10600 -525);
FORCEPROP 2 LAST CDS_LIB standard
J 2
(-10925 -400);
PAINT MONO (-10925 -400);
DISPLAY INVISIBLE (-10925 -400);
FORCEADD OFFPAGE..1
(-10925 -450);
FORCEPROP 2 LAST $XR0 128 
J 0
(-11207 -450);
DISPLAY 0.638298 (-11207 -450);
PAINT MONO (-11207 -450);
FORCEPROP 2 LAST PATH I64
J 0
(-11200 -400);
DISPLAY 1.021277 (-11200 -400);
DISPLAY INVISIBLE (-11200 -400);
FORCEPROP 1 LAST COMMENT_BODY TRUE
J 0
(-10800 -550);
DISPLAY 1.170213 (-10800 -550);
PAINT GREEN (-10800 -550);
DISPLAY INVISIBLE (-10800 -550);
FORCEPROP 1 LAST OFFPAGE TRUE
J 0
(-10600 -575);
DISPLAY 1.170213 (-10600 -575);
PAINT GREEN (-10600 -575);
DISPLAY INVISIBLE (-10600 -575);
FORCEPROP 2 LAST CDS_LIB standard
J 2
(-10925 -450);
PAINT MONO (-10925 -450);
DISPLAY INVISIBLE (-10925 -450);
FORCEADD OFFPAGE..1
(-10925 -500);
FORCEPROP 2 LAST $XR0 128 
J 0
(-11207 -500);
DISPLAY 0.638298 (-11207 -500);
PAINT MONO (-11207 -500);
FORCEPROP 2 LAST PATH I65
J 0
(-11200 -450);
DISPLAY 1.021277 (-11200 -450);
DISPLAY INVISIBLE (-11200 -450);
FORCEPROP 2 LAST CDS_LIB standard
J 2
(-10925 -500);
PAINT MONO (-10925 -500);
DISPLAY INVISIBLE (-10925 -500);
FORCEPROP 1 LAST OFFPAGE TRUE
J 0
(-10600 -625);
DISPLAY 1.170213 (-10600 -625);
PAINT GREEN (-10600 -625);
DISPLAY INVISIBLE (-10600 -625);
FORCEPROP 1 LAST COMMENT_BODY TRUE
J 0
(-10800 -600);
DISPLAY 1.170213 (-10800 -600);
PAINT GREEN (-10800 -600);
DISPLAY INVISIBLE (-10800 -600);
FORCEADD Q_RES..1
(-7600 1875);
FORCEPROP 1 LAST PART_NUMBER CS21002FB06
J 0
(-7725 1825);
DISPLAY 0.510638 (-7725 1825);
DISPLAY INVISIBLE (-7725 1825);
FORCEPROP 1 LAST MATERIAL CHIP
J 0
(-7500 1875);
DISPLAY 0.510638 (-7500 1875);
FORCEPROP 1 LAST VALUE 1K
J 2
(-7650 1850);
DISPLAY 0.510638 (-7650 1850);
FORCEPROP 1 LAST $LOCATION R4053
J 0
(-7775 1875);
DISPLAY 0.510638 (-7775 1875);
FORCEPROP 1 LASTPIN (-7700 1875) $PN 1
J 0
(-7688 1887);
DISPLAY 0.787234 (-7688 1887);
PAINT MONO (-7688 1887);
FORCEPROP 1 LASTPIN (-7500 1875) $PN 2
J 0
(-7538 1887);
DISPLAY 0.787234 (-7538 1887);
PAINT MONO (-7538 1887);
FORCEPROP 1 LAST PATH I66
J 0
(-7650 2025);
DISPLAY 0.978723 (-7650 2025);
PAINT WHITE (-7650 2025);
DISPLAY INVISIBLE (-7650 2025);
FORCEPROP 2 LAST CDS_LIB pure_quanta
J 0
(-7600 1875);
DISPLAY INVISIBLE (-7600 1875);
FORCEPROP 1 LAST PACK_TYPE 0402LF
J 0
(-7850 1850);
DISPLAY 0.510638 (-7850 1850);
DISPLAY INVISIBLE (-7850 1850);
FORCEPROP 1 LAST WATTAGE 1/16W
J 2
(-7950 1850);
DISPLAY 0.510638 (-7950 1850);
DISPLAY INVISIBLE (-7950 1850);
FORCEPROP 1 LAST TOLERANCE 1%
J 0
(-7900 1850);
DISPLAY 0.510638 (-7900 1850);
DISPLAY INVISIBLE (-7900 1850);
FORCEPROP 0 LAST CDS_LOCATION R4053
J 0
(-7750 1925);
DISPLAY 1.021277 (-7750 1925);
DISPLAY INVISIBLE (-7750 1925);
FORCEPROP 0 LAST $SEC 1
J 0
(-7750 1925);
DISPLAY 0.680851 (-7750 1925);
PAINT MONO (-7750 1925);
DISPLAY INVISIBLE (-7750 1925);
FORCEPROP 0 LAST CDS_SEC 1
J 0
(-7750 1925);
DISPLAY 1.021277 (-7750 1925);
DISPLAY INVISIBLE (-7750 1925);
FORCEADD Q_RES..1
(-7600 -200);
FORCEPROP 1 LAST PART_NUMBER CS21002FB06
J 0
(-7725 -250);
DISPLAY 0.510638 (-7725 -250);
DISPLAY INVISIBLE (-7725 -250);
FORCEPROP 1 LAST VALUE 1K
J 2
(-7650 -225);
DISPLAY 0.510638 (-7650 -225);
FORCEPROP 1 LAST MATERIAL CHIP
J 0
(-7500 -200);
DISPLAY 0.510638 (-7500 -200);
FORCEPROP 1 LAST $LOCATION R4054
J 0
(-7825 -200);
DISPLAY 0.638298 (-7825 -200);
FORCEPROP 1 LASTPIN (-7700 -200) $PN 1
J 0
(-7688 -188);
DISPLAY 0.787234 (-7688 -188);
PAINT MONO (-7688 -188);
FORCEPROP 1 LASTPIN (-7500 -200) $PN 2
J 0
(-7538 -188);
DISPLAY 0.787234 (-7538 -188);
PAINT MONO (-7538 -188);
FORCEPROP 1 LAST PATH I67
J 0
(-7650 -50);
DISPLAY 0.978723 (-7650 -50);
PAINT WHITE (-7650 -50);
DISPLAY INVISIBLE (-7650 -50);
FORCEPROP 2 LAST CDS_LIB pure_quanta
J 0
(-7600 -200);
DISPLAY INVISIBLE (-7600 -200);
FORCEPROP 1 LAST TOLERANCE 1%
J 0
(-7900 -225);
DISPLAY 0.510638 (-7900 -225);
DISPLAY INVISIBLE (-7900 -225);
FORCEPROP 1 LAST WATTAGE 1/16W
J 2
(-7950 -225);
DISPLAY 0.510638 (-7950 -225);
DISPLAY INVISIBLE (-7950 -225);
FORCEPROP 1 LAST PACK_TYPE 0402LF
J 0
(-7850 -225);
DISPLAY 0.510638 (-7850 -225);
DISPLAY INVISIBLE (-7850 -225);
FORCEPROP 0 LAST CDS_LOCATION R4054
J 0
(-7650 -100);
DISPLAY 1.021277 (-7650 -100);
DISPLAY INVISIBLE (-7650 -100);
FORCEPROP 0 LAST $SEC 1
J 0
(-7650 -100);
DISPLAY 0.680851 (-7650 -100);
PAINT MONO (-7650 -100);
DISPLAY INVISIBLE (-7650 -100);
FORCEPROP 0 LAST CDS_SEC 1
J 0
(-7650 -100);
DISPLAY 1.021277 (-7650 -100);
DISPLAY INVISIBLE (-7650 -100);
FORCEADD UNIVERSAL_GND..1
(-10000 1275);
FORCEPROP 3 LASTPIN (-10000 1325) SIG_NAME GND\g
J 0
(-9990 1335);
DISPLAY 0.659574 (-9990 1335);
PAINT MONO (-9990 1335);
DISPLAY INVISIBLE (-9990 1335);
FORCEPROP 1 LAST PATH I8
J 0
(-9925 1275);
DISPLAY 0.872340 (-9925 1275);
PAINT AQUA (-9925 1275);
DISPLAY INVISIBLE (-9925 1275);
FORCEPROP 1 LAST HDL_POWER GND
J 1
(-9975 1200);
DISPLAY 0.872340 (-9975 1200);
PAINT GREEN (-9975 1200);
DISPLAY INVISIBLE (-9975 1200);
FORCEPROP 2 LAST CDS_LIB logical_power
J 0
(-10000 1275);
DISPLAY INVISIBLE (-10000 1275);
FORCEADD GTL2014PW..1
R 2
(-9475 -2300);
FORCEPROP 1 LAST PART_NUMBER AL002014K01
J 2
(-9227 -1895);
DISPLAY 0.723404 (-9227 -1895);
PAINT GREEN (-9227 -1895);
DISPLAY INVISIBLE (-9227 -1895);
FORCEPROP 1 LAST MATERIAL IC
J 2
(-9227 -1945);
DISPLAY 0.723404 (-9227 -1945);
PAINT GREEN (-9227 -1945);
FORCEPROP 2 LAST VALUE GTL2014PW
J 2
(-9250 -1800);
DISPLAY 1.021277 (-9250 -1800);
FORCEPROP 2 LAST PART_TYPE SMLF
J 2
(-9250 -1750);
DISPLAY 1.021277 (-9250 -1750);
FORCEPROP 1 LAST $LOCATION U306
J 2
(-9227 -1850);
DISPLAY 0.680851 (-9227 -1850);
PAINT GREEN (-9227 -1850);
FORCEPROP 2 LASTPIN (-9075 -2400) $PN 13
J 0
(-9065 -2390);
DISPLAY 0.680851 (-9065 -2390);
PAINT MONO (-9065 -2390);
FORCEPROP 2 LASTPIN (-9075 -2350) $PN 12
J 0
(-9065 -2340);
DISPLAY 0.680851 (-9065 -2340);
PAINT MONO (-9065 -2340);
FORCEPROP 2 LASTPIN (-9075 -2300) $PN 10
J 0
(-9065 -2290);
DISPLAY 0.680851 (-9065 -2290);
PAINT MONO (-9065 -2290);
FORCEPROP 2 LASTPIN (-9075 -2250) $PN 9
J 0
(-9065 -2240);
DISPLAY 0.680851 (-9065 -2240);
PAINT MONO (-9065 -2240);
FORCEPROP 2 LASTPIN (-9875 -2400) $PN 2
J 2
(-9885 -2390);
DISPLAY 0.680851 (-9885 -2390);
PAINT MONO (-9885 -2390);
FORCEPROP 2 LASTPIN (-9875 -2350) $PN 3
J 2
(-9885 -2340);
DISPLAY 0.680851 (-9885 -2340);
PAINT MONO (-9885 -2340);
FORCEPROP 2 LASTPIN (-9875 -2300) $PN 5
J 2
(-9885 -2290);
DISPLAY 0.680851 (-9885 -2290);
PAINT MONO (-9885 -2290);
FORCEPROP 2 LASTPIN (-9875 -2250) $PN 6
J 2
(-9885 -2240);
DISPLAY 0.680851 (-9885 -2240);
PAINT MONO (-9885 -2240);
FORCEPROP 2 LASTPIN (-9075 -2150) $PN 1
J 0
(-9065 -2140);
DISPLAY 0.680851 (-9065 -2140);
PAINT MONO (-9065 -2140);
FORCEPROP 2 LASTPIN (-9875 -2600) $PN 7
J 2
(-9885 -2590);
DISPLAY 0.680851 (-9885 -2590);
PAINT MONO (-9885 -2590);
FORCEPROP 2 LASTPIN (-9875 -2550) $PN 8
J 2
(-9885 -2540);
DISPLAY 0.680851 (-9885 -2540);
PAINT MONO (-9885 -2540);
FORCEPROP 2 LASTPIN (-9875 -2500) $PN 11
J 2
(-9885 -2490);
DISPLAY 0.680851 (-9885 -2490);
PAINT MONO (-9885 -2490);
FORCEPROP 2 LASTPIN (-9075 -2000) $PN 14
J 0
(-9065 -1990);
DISPLAY 0.680851 (-9065 -1990);
PAINT MONO (-9065 -1990);
FORCEPROP 2 LASTPIN (-9075 -2050) $PN 4
J 0
(-9065 -2040);
DISPLAY 0.680851 (-9065 -2040);
PAINT MONO (-9065 -2040);
FORCEPROP 2 LAST SEC_TYPE 
J 2
(-9250 -1700);
DISPLAY 1.021277 (-9250 -1700);
DISPLAY INVISIBLE (-9250 -1700);
FORCEPROP 2 LAST CDS_LIB pure_quanta
J 2
(-9475 -2300);
PAINT RED (-9475 -2300);
DISPLAY INVISIBLE (-9475 -2300);
FORCEPROP 1 LAST CDS_LMAN_SYM_OUTLINE -250,350,250,-350
J 2
(-9475 -2300);
DISPLAY 0.468085 (-9475 -2300);
PAINT GREEN (-9475 -2300);
DISPLAY INVISIBLE (-9475 -2300);
FORCEPROP 1 LAST NEEDS_NO_SIZE TRUE
J 2
(-9475 -2300);
DISPLAY 0.723404 (-9475 -2300);
PAINT GREEN (-9475 -2300);
DISPLAY INVISIBLE (-9475 -2300);
FORCEPROP 1 LAST PATH I80
J 2
(-9475 -2300);
DISPLAY 0.723404 (-9475 -2300);
PAINT GREEN (-9475 -2300);
DISPLAY INVISIBLE (-9475 -2300);
FORCEPROP 2 LAST CDS_LOCATION U306
J 0
(-9250 -1700);
DISPLAY 1.021277 (-9250 -1700);
DISPLAY INVISIBLE (-9250 -1700);
FORCEPROP 2 LAST SEC 1
J 2
(-9250 -1700);
DISPLAY 0.680851 (-9250 -1700);
PAINT MONO (-9250 -1700);
DISPLAY INVISIBLE (-9250 -1700);
FORCEADD Q_CAP..1
(-8825 -1675);
FORCEPROP 1 LAST PART_NUMBER CH5104KEB02
J 0
(-8775 -1825);
DISPLAY 0.404255 (-8775 -1825);
DISPLAY INVISIBLE (-8775 -1825);
FORCEPROP 1 LAST VALUE 1UF
J 0
(-8775 -1625);
DISPLAY 0.510638 (-8775 -1625);
FORCEPROP 1 LAST PACK_TYPE C0402
J 0
(-8775 -1875);
DISPLAY 0.510638 (-8775 -1875);
FORCEPROP 1 LAST MATERIAL X6S
J 0
(-8775 -1775);
DISPLAY 0.510638 (-8775 -1775);
FORCEPROP 1 LAST VOLTAGE 25V
J 0
(-8775 -1675);
DISPLAY 0.510638 (-8775 -1675);
FORCEPROP 1 LAST TOLERANCE 10%
J 0
(-8775 -1725);
DISPLAY 0.510638 (-8775 -1725);
FORCEPROP 1 LAST $LOCATION C2248
J 0
(-8775 -1575);
DISPLAY 0.978723 (-8775 -1575);
FORCEPROP 1 LASTPIN (-8825 -1575) $PN 1
J 0
(-8815 -1595);
DISPLAY 0.787234 (-8815 -1595);
FORCEPROP 1 LASTPIN (-8825 -1775) $PN 2
J 0
(-8815 -1795);
DISPLAY 0.787234 (-8815 -1795);
FORCEPROP 2 LAST CDS_LIB pure_quanta
J 0
(-8825 -1675);
DISPLAY INVISIBLE (-8825 -1675);
FORCEPROP 1 LAST PATH I83
J 0
(-8775 -1525);
DISPLAY 0.978723 (-8775 -1525);
PAINT WHITE (-8775 -1525);
DISPLAY INVISIBLE (-8775 -1525);
FORCEPROP 2 LAST CDS_LOCATION C2248
J 0
(-8775 -1475);
DISPLAY 1.021277 (-8775 -1475);
DISPLAY INVISIBLE (-8775 -1475);
FORCEPROP 2 LAST $SEC 1
J 0
(-8775 -1475);
DISPLAY 0.680851 (-8775 -1475);
PAINT MONO (-8775 -1475);
DISPLAY INVISIBLE (-8775 -1475);
FORCEPROP 2 LAST CDS_SEC 1
J 0
(-8775 -1475);
DISPLAY 0.680851 (-8775 -1475);
DISPLAY INVISIBLE (-8775 -1475);
FORCEADD UNIVERSAL_POWER..1
(-8975 -1425);
FORCEPROP 3 LASTPIN (-8975 -1475) SIG_NAME P3V3\g
J 0
(-8965 -1465);
DISPLAY 0.659574 (-8965 -1465);
PAINT MONO (-8965 -1465);
DISPLAY INVISIBLE (-8965 -1465);
FORCEPROP 1 LAST HDL_POWER P3V3
J 1
(-8975 -1375);
DISPLAY 0.872340 (-8975 -1375);
PAINT GREEN (-8975 -1375);
FORCEPROP 2 LAST CDS_LIB logical_power
J 0
(-8975 -1425);
PAINT RED (-8975 -1425);
DISPLAY INVISIBLE (-8975 -1425);
FORCEPROP 1 LAST PATH I84
J 0
(-8925 -1400);
DISPLAY 0.872340 (-8925 -1400);
PAINT AQUA (-8925 -1400);
DISPLAY INVISIBLE (-8925 -1400);
FORCEADD UNIVERSAL_GND..1
R 2
(-7125 -2175);
FORCEPROP 3 LASTPIN (-7125 -2125) SIG_NAME GND\g
J 0
(-7115 -2115);
DISPLAY 0.659574 (-7115 -2115);
PAINT MONO (-7115 -2115);
DISPLAY INVISIBLE (-7115 -2115);
FORCEPROP 1 LAST HDL_POWER GND
J 1
(-7150 -2250);
DISPLAY 0.872340 (-7150 -2250);
PAINT GREEN (-7150 -2250);
DISPLAY INVISIBLE (-7150 -2250);
FORCEPROP 2 LAST CDS_LIB logical_power
R 3
J 0
(-7125 -2175);
PAINT MONO (-7125 -2175);
DISPLAY INVISIBLE (-7125 -2175);
FORCEPROP 1 LAST PATH I89
J 2
(-7200 -2175);
DISPLAY 0.872340 (-7200 -2175);
PAINT AQUA (-7200 -2175);
DISPLAY INVISIBLE (-7200 -2175);
FORCEADD Q_CAP..1
(-8825 2300);
FORCEPROP 1 LAST PART_NUMBER CH5104KEB02
J 0
(-8775 2150);
DISPLAY 0.404255 (-8775 2150);
DISPLAY INVISIBLE (-8775 2150);
FORCEPROP 1 LAST TOLERANCE 10%
J 0
(-8775 2250);
DISPLAY 0.510638 (-8775 2250);
FORCEPROP 1 LAST MATERIAL X6S
J 0
(-8775 2200);
DISPLAY 0.510638 (-8775 2200);
FORCEPROP 1 LAST VOLTAGE 25V
J 0
(-8775 2300);
DISPLAY 0.510638 (-8775 2300);
FORCEPROP 1 LAST VALUE 1UF
J 0
(-8775 2350);
DISPLAY 0.510638 (-8775 2350);
FORCEPROP 1 LAST PACK_TYPE C0402
J 0
(-8775 2100);
DISPLAY 0.510638 (-8775 2100);
FORCEPROP 1 LAST $LOCATION C2246
J 0
(-8775 2400);
DISPLAY 0.978723 (-8775 2400);
FORCEPROP 1 LASTPIN (-8825 2400) $PN 1
J 0
(-8815 2380);
DISPLAY 0.787234 (-8815 2380);
FORCEPROP 1 LASTPIN (-8825 2200) $PN 2
J 0
(-8815 2180);
DISPLAY 0.787234 (-8815 2180);
FORCEPROP 1 LAST PATH I9
J 0
(-8775 2450);
DISPLAY 0.978723 (-8775 2450);
PAINT WHITE (-8775 2450);
DISPLAY INVISIBLE (-8775 2450);
FORCEPROP 2 LAST CDS_LIB pure_quanta
J 0
(-8825 2300);
DISPLAY INVISIBLE (-8825 2300);
FORCEPROP 2 LAST CDS_LOCATION C2246
J 0
(-8775 2500);
DISPLAY 1.021277 (-8775 2500);
DISPLAY INVISIBLE (-8775 2500);
FORCEPROP 2 LAST $SEC 1
J 0
(-8775 2500);
DISPLAY 0.680851 (-8775 2500);
PAINT MONO (-8775 2500);
DISPLAY INVISIBLE (-8775 2500);
FORCEPROP 2 LAST CDS_SEC 1
J 0
(-8775 2500);
DISPLAY 0.680851 (-8775 2500);
DISPLAY INVISIBLE (-8775 2500);
FORCEADD Q_RES..1
(-7575 -2150);
FORCEPROP 1 LAST PART_NUMBER CS21002FB06
J 0
(-7700 -2200);
DISPLAY 0.510638 (-7700 -2200);
DISPLAY INVISIBLE (-7700 -2200);
FORCEPROP 1 LAST VALUE 1K
J 2
(-7625 -2175);
DISPLAY 0.510638 (-7625 -2175);
FORCEPROP 1 LAST MATERIAL CHIP
J 0
(-7875 -2150);
DISPLAY 0.510638 (-7875 -2150);
FORCEPROP 1 LAST WATTAGE 1/16W
J 2
(-7925 -2175);
DISPLAY 0.510638 (-7925 -2175);
FORCEPROP 1 LAST TOLERANCE 1%
J 0
(-7875 -2175);
DISPLAY 0.510638 (-7875 -2175);
FORCEPROP 1 LAST PACK_TYPE 0402LF
J 0
(-7825 -2175);
DISPLAY 0.510638 (-7825 -2175);
FORCEPROP 1 LAST $LOCATION R4055
J 0
(-7625 -2100);
DISPLAY 0.978723 (-7625 -2100);
FORCEPROP 1 LASTPIN (-7675 -2150) $PN 1
J 0
(-7663 -2138);
DISPLAY 0.787234 (-7663 -2138);
PAINT MONO (-7663 -2138);
FORCEPROP 1 LASTPIN (-7475 -2150) $PN 2
J 0
(-7513 -2138);
DISPLAY 0.787234 (-7513 -2138);
PAINT MONO (-7513 -2138);
FORCEPROP 2 LAST CDS_LIB pure_quanta
J 0
(-7575 -2150);
DISPLAY INVISIBLE (-7575 -2150);
FORCEPROP 1 LAST PATH I91
J 0
(-7625 -2000);
DISPLAY 0.978723 (-7625 -2000);
PAINT WHITE (-7625 -2000);
DISPLAY INVISIBLE (-7625 -2000);
FORCEPROP 0 LAST CDS_LOCATION R4055
J 0
(-7625 -2050);
DISPLAY 1.021277 (-7625 -2050);
DISPLAY INVISIBLE (-7625 -2050);
FORCEPROP 0 LAST $SEC 1
J 0
(-7625 -2050);
DISPLAY 0.680851 (-7625 -2050);
PAINT MONO (-7625 -2050);
DISPLAY INVISIBLE (-7625 -2050);
FORCEPROP 0 LAST CDS_SEC 1
J 0
(-7625 -2050);
DISPLAY 1.021277 (-7625 -2050);
DISPLAY INVISIBLE (-7625 -2050);
FORCEADD Q_RES..1
(-5800 -2300);
FORCEPROP 1 LAST PART_NUMBER CS03322FB03
J 0
(-5925 -2400);
DISPLAY 0.510638 (-5925 -2400);
DISPLAY INVISIBLE (-5925 -2400);
FORCEPROP 1 LAST MATERIAL CHIP
J 0
(-5575 -2300);
DISPLAY 0.510638 (-5575 -2300);
FORCEPROP 1 LAST VALUE 33.2
J 2
(-5600 -2300);
DISPLAY 0.510638 (-5600 -2300);
FORCEPROP 1 LAST $LOCATION R4051
J 0
(-6000 -2300);
DISPLAY 0.638298 (-6000 -2300);
FORCEPROP 1 LASTPIN (-5900 -2300) $PN 1
J 0
(-5888 -2288);
DISPLAY 0.787234 (-5888 -2288);
PAINT MONO (-5888 -2288);
FORCEPROP 1 LASTPIN (-5700 -2300) $PN 2
J 0
(-5738 -2288);
DISPLAY 0.787234 (-5738 -2288);
PAINT MONO (-5738 -2288);
FORCEPROP 1 LAST PATH I94
J 0
(-5850 -2150);
DISPLAY 0.978723 (-5850 -2150);
PAINT WHITE (-5850 -2150);
DISPLAY INVISIBLE (-5850 -2150);
FORCEPROP 1 LAST WATTAGE 1/16W
J 2
(-5650 -2350);
DISPLAY 0.510638 (-5650 -2350);
DISPLAY INVISIBLE (-5650 -2350);
FORCEPROP 1 LAST TOLERANCE 1%
J 0
(-5575 -2300);
DISPLAY 0.510638 (-5575 -2300);
DISPLAY INVISIBLE (-5575 -2300);
FORCEPROP 1 LAST PACK_TYPE 0402LF
J 0
(-5500 -2300);
DISPLAY 0.510638 (-5500 -2300);
DISPLAY INVISIBLE (-5500 -2300);
FORCEPROP 2 LAST CDS_LIB pure_quanta
J 0
(-5800 -2300);
DISPLAY INVISIBLE (-5800 -2300);
FORCEPROP 0 LAST CDS_LOCATION R4051
J 0
(-5975 -2250);
DISPLAY 1.021277 (-5975 -2250);
DISPLAY INVISIBLE (-5975 -2250);
FORCEPROP 0 LAST $SEC 1
J 0
(-5975 -2250);
DISPLAY 0.680851 (-5975 -2250);
PAINT MONO (-5975 -2250);
DISPLAY INVISIBLE (-5975 -2250);
FORCEPROP 0 LAST CDS_SEC 1
J 0
(-5975 -2250);
DISPLAY 1.021277 (-5975 -2250);
DISPLAY INVISIBLE (-5975 -2250);
FORCEADD UNIVERSAL_GND..1
(-8825 -1900);
FORCEPROP 3 LASTPIN (-8825 -1850) SIG_NAME GND\g
J 0
(-8815 -1840);
DISPLAY 0.659574 (-8815 -1840);
PAINT MONO (-8815 -1840);
DISPLAY INVISIBLE (-8815 -1840);
FORCEPROP 1 LAST HDL_POWER GND
J 1
(-8800 -1975);
DISPLAY 0.872340 (-8800 -1975);
PAINT GREEN (-8800 -1975);
DISPLAY INVISIBLE (-8800 -1975);
FORCEPROP 2 LAST CDS_LIB logical_power
J 0
(-8825 -1900);
DISPLAY INVISIBLE (-8825 -1900);
FORCEPROP 1 LAST PATH I96
J 0
(-8750 -1900);
DISPLAY 0.872340 (-8750 -1900);
PAINT AQUA (-8750 -1900);
DISPLAY INVISIBLE (-8750 -1900);
FORCEADD UNIVERSAL_GND..1
(-10000 -2700);
FORCEPROP 3 LASTPIN (-10000 -2650) SIG_NAME GND\g
J 0
(-9990 -2640);
DISPLAY 0.659574 (-9990 -2640);
PAINT MONO (-9990 -2640);
DISPLAY INVISIBLE (-9990 -2640);
FORCEPROP 2 LAST CDS_LIB logical_power
J 0
(-10000 -2700);
DISPLAY INVISIBLE (-10000 -2700);
FORCEPROP 1 LAST HDL_POWER GND
J 1
(-9975 -2775);
DISPLAY 0.872340 (-9975 -2775);
PAINT GREEN (-9975 -2775);
DISPLAY INVISIBLE (-9975 -2775);
FORCEPROP 1 LAST PATH I97
J 0
(-9925 -2700);
DISPLAY 0.872340 (-9925 -2700);
PAINT AQUA (-9925 -2700);
DISPLAY INVISIBLE (-9925 -2700);
FORCEADD QUANTA_TITLE_BLOCK_C..1
(-4250 -3550);
FORCEPROP 0 LAST CDS_CON_LAST_MODIFIED Fri Aug 25 14:03:46 2023
J 0
(-6135 -3535);
DISPLAY INVISIBLE (-6135 -3535);
FORCEPROP 1 LAST CUSTOM_TXT_CDS <CON_LAST_MODIFIED>
J 0
(-6135 -3535);
DISPLAY 0.978723 (-6135 -3535);
FORCEPROP 2 LAST CUSTOM_TXT_CDS <XR_PAGE_TITLE>
J 0
(-12140 1700);
DISPLAY 0.638298 (-12140 1700);
PAINT PINK (-12140 1700);
DISPLAY INVISIBLE (-12140 1700);
FORCEPROP 1 LAST CUSTOM_TXT_CDS <NAME_2>
J 0
(-7425 -3500);
FORCEPROP 1 LAST CUSTOM_TXT_CDS <NAME_1>
J 0
(-7425 -3375);
FORCEPROP 1 LAST CUSTOM_TXT_CDS <Q_NUMBER>
J 0
(-5653 -3447);
DISPLAY 1.212766 (-5653 -3447);
FORCEPROP 1 LAST CUSTOM_TXT_CDS <Q_PROJ>
J 0
(-6632 -3448);
DISPLAY 1.212766 (-6632 -3448);
FORCEPROP 1 LAST CUSTOM_TXT_CDS <Q_REV>
J 0
(-4434 -3447);
DISPLAY 1.212766 (-4434 -3447);
FORCEPROP 1 LAST CUSTOM_TXT_CDS <CON_PAGE_NUM> OF <CON_TOTAL_PAGES>
J 0
(-4696 -3532);
DISPLAY 0.978723 (-4696 -3532);
FORCEPROP 1 LAST Q_TITLE GTL2014(1/2)
J 0
(-13616 -3524);
DISPLAY 2.446809 (-13616 -3524);
PAINT GREEN (-13616 -3524);
FORCEPROP 1 LAST Q_DEPT 
J 1
(-8013 -3501);
DISPLAY 1.957447 (-8013 -3501);
PAINT GREEN (-8013 -3501);
FORCEPROP 2 LAST CDS_XR_PAGE_TITLE CR-225 : @S9S_MB_2U_LIB.S9S_MB_2U(SCH_1):PAGE225
J 0
(-12140 1700);
DISPLAY 0.638298 (-12140 1700);
PAINT PINK (-12140 1700);
DISPLAY INVISIBLE (-12140 1700);
FORCEPROP 2 LAST CDS_LIB pure_quanta
J 0
(-4250 -3550);
DISPLAY INVISIBLE (-4250 -3550);
FORCEPROP 1 LAST CDS_LMAN_SYM_OUTLINE -9475,6775,100,-125
J 0
(-4250 -3550);
DISPLAY 0.468085 (-4250 -3550);
PAINT GREEN (-4250 -3550);
DISPLAY INVISIBLE (-4250 -3550);
FORCEPROP 2 LAST PAGE_BORDER TRUE
J 0
(-12140 1700);
DISPLAY 0.638298 (-12140 1700);
PAINT PINK (-12140 1700);
DISPLAY INVISIBLE (-12140 1700);
FORCEPROP 1 LAST COMMENT_BODY TRUE
J 0
(-4238 -3563);
DISPLAY 0.978723 (-4238 -3563);
PAINT GREEN (-4238 -3563);
DISPLAY INVISIBLE (-4238 -3563);
WIRE 16 -1 (-8975 -1475)(-8975 -1525);
WIRE 16 -1 (-7850 -1250)(-7850 -1325);
WIRE 16 -1 (-7850 2750)(-7850 2650);
WIRE 16 -1 (-8975 425)(-8975 375);
WIRE 16 -1 (-7850 675)(-7850 575);
WIRE 16 -1 (-12075 -2675)(-12075 -2725);
WIRE 16 -1 (-12050 -900)(-12050 -950);
WIRE 16 -1 (-12075 -1825)(-12075 -1875);
WIRE 16 -1 (-8975 2500)(-8975 2450);
WIRE 16 -1 (-7850 -2025)(-7850 -2000);
WIRE 16 -1 (-10425 -3125)(-10425 -3200);
WIRE 16 -1 (-7850 -125)(-7850 -100);
WIRE 16 -1 (-7850 1950)(-7850 1975);
WIRE 16 -1 (-10000 -750)(-10000 -700);
WIRE 16 -1 (-8825 125)(-8825 50);
WIRE 16 -1 (-7125 -225)(-7125 -200);
WIRE 16 -1 (-7125 -2125)(-7125 -2100);
WIRE 16 -1 (-8825 -1775)(-8825 -1850);
WIRE 16 -1 (-10000 -2650)(-10000 -2600);
WIRE 16 -1 (-10000 1325)(-10000 1375);
WIRE 16 -1 (-8825 2200)(-8825 2125);
WIRE 16 -1 (-7125 1850)(-7125 1875);
WIRE 16 -1 (-9875 -2250)(-10500 -2250);
FORCEPROP 0 LAST CDS_PHYS_NET_NAME H_CPU_ERR0_LVC1_N
J 0
(-10475 -2208);
PAINT MONO (-10475 -2208);
DISPLAY INVISIBLE (-10475 -2208);
FORCEPROP 0 LAST SIG_NAME H_CPU_ERR0_LVC1_N
J 0
(-11035 -1365);
DISPLAY 0.680851 (-11035 -1365);
PAINT WHITE (-11035 -1365);
WIRE 16 -1 (-10500 -1375)(-10500 -2250);
WIRE 16 -1 (-11225 -1375)(-10500 -1375);
WIRE 16 -1 (-9075 -100)(-8975 -100);
WIRE 16 -1 (-8975 -100)(-8975 375);
WIRE 16 -1 (-8975 375)(-8825 375);
WIRE 16 -1 (-8825 325)(-8825 375);
WIRE 16 -1 (-7850 250)(-7850 200);
WIRE 16 -1 (-7850 375)(-7850 250);
WIRE 16 -1 (-8225 250)(-8225 200);
WIRE 16 -1 (-7850 250)(-8225 250);
WIRE 16 -1 (-8400 250)(-8225 250);
WIRE 16 -1 (-8400 -150)(-8400 250);
WIRE 16 -1 (-9075 -150)(-8400 -150);
FORCEPROP 2 LAST SIG_NAME P0V62_CPU1_RST_DDR_VREF
J 0
(-8950 -140);
DISPLAY 0.446809 (-8950 -140);
PAINT WHITE (-8950 -140);
WIRE 16 -1 (-7700 -200)(-8125 -200);
WIRE 16 -1 (-8125 -250)(-9075 -250);
FORCEPROP 2 LAST SIG_NAME PD_GTL2014_BMC_JTAG_DIR_1
J 0
(-8950 -240);
DISPLAY 0.446809 (-8950 -240);
PAINT WHITE (-8950 -240);
WIRE 16 -1 (-8125 -250)(-8125 -200);
WIRE 16 -1 (-9075 -500)(-7800 -500);
FORCEPROP 0 LAST CDS_PHYS_NET_NAME RST_CPU0_DRAM_GH_PLD_N
J 0
(-9050 -458);
PAINT MONO (-9050 -458);
DISPLAY INVISIBLE (-9050 -458);
FORCEPROP 0 LAST SIG_NAME RST_CPU1_DRAM_GH_PLD_LVT3_R_N
J 0
(-8935 -490);
DISPLAY 0.680851 (-8935 -490);
PAINT WHITE (-8935 -490);
WIRE 16 -1 (-9075 -450)(-7800 -450);
FORCEPROP 0 LAST CDS_PHYS_NET_NAME RST_CPU0_DRAM_EF_PLD_N
J 0
(-9050 -408);
PAINT MONO (-9050 -408);
DISPLAY INVISIBLE (-9050 -408);
FORCEPROP 0 LAST SIG_NAME RST_CPU1_DRAM_EF_PLD_LVT3_R_N
J 0
(-8935 -440);
DISPLAY 0.680851 (-8935 -440);
PAINT WHITE (-8935 -440);
WIRE 16 -1 (-9075 -400)(-7800 -400);
FORCEPROP 0 LAST CDS_PHYS_NET_NAME RST_CPU0_DRAM_CD_PLD_N
J 0
(-9050 -358);
PAINT MONO (-9050 -358);
DISPLAY INVISIBLE (-9050 -358);
FORCEPROP 0 LAST SIG_NAME RST_CPU1_DRAM_CD_PLD_LVT3_R_N
J 0
(-8935 -390);
DISPLAY 0.680851 (-8935 -390);
PAINT WHITE (-8935 -390);
WIRE 16 -1 (-9075 -350)(-7800 -350);
FORCEPROP 0 LAST CDS_PHYS_NET_NAME RST_CPU0_DRAM_AB_PLD_N
J 0
(-9050 -308);
PAINT MONO (-9050 -308);
DISPLAY INVISIBLE (-9050 -308);
FORCEPROP 0 LAST SIG_NAME RST_CPU1_DRAM_AB_PLD_LVT3_R_N
J 0
(-8935 -340);
DISPLAY 0.680851 (-8935 -340);
PAINT WHITE (-8935 -340);
WIRE 16 -1 (-9875 -700)(-10000 -700);
WIRE 16 -1 (-10000 -650)(-10000 -700);
WIRE 16 -1 (-10000 -650)(-9875 -650);
WIRE 16 -1 (-10000 -600)(-10000 -650);
WIRE 16 -1 (-10000 -600)(-9875 -600);
WIRE 16 -1 (-10875 -350)(-9875 -350);
FORCEPROP 0 LAST CDS_PHYS_NET_NAME RST_CPU1_DRAM_AB_PLD_N
J 0
(-10850 -308);
PAINT MONO (-10850 -308);
DISPLAY INVISIBLE (-10850 -308);
FORCEPROP 0 LAST SIG_NAME RST_CPU1_DRAM_AB_PLD_N
J 0
(-10735 -340);
DISPLAY 0.680851 (-10735 -340);
PAINT WHITE (-10735 -340);
WIRE 16 -1 (-10875 -400)(-9875 -400);
FORCEPROP 0 LAST CDS_PHYS_NET_NAME RST_CPU1_DRAM_CD_PLD_N
J 0
(-10850 -358);
PAINT MONO (-10850 -358);
DISPLAY INVISIBLE (-10850 -358);
FORCEPROP 0 LAST SIG_NAME RST_CPU1_DRAM_CD_PLD_N
J 0
(-10735 -390);
DISPLAY 0.680851 (-10735 -390);
PAINT WHITE (-10735 -390);
WIRE 16 -1 (-10875 -450)(-9875 -450);
FORCEPROP 0 LAST CDS_PHYS_NET_NAME RST_CPU1_DRAM_EF_PLD_N
J 0
(-10850 -408);
PAINT MONO (-10850 -408);
DISPLAY INVISIBLE (-10850 -408);
FORCEPROP 0 LAST SIG_NAME RST_CPU1_DRAM_EF_PLD_N
J 0
(-10735 -440);
DISPLAY 0.680851 (-10735 -440);
PAINT WHITE (-10735 -440);
WIRE 16 -1 (-10875 -500)(-9875 -500);
FORCEPROP 0 LAST CDS_PHYS_NET_NAME RST_CPU1_DRAM_GH_PLD_N
J 0
(-10850 -458);
PAINT MONO (-10850 -458);
DISPLAY INVISIBLE (-10850 -458);
FORCEPROP 0 LAST SIG_NAME RST_CPU1_DRAM_GH_PLD_N
J 0
(-10735 -490);
DISPLAY 0.680851 (-10735 -490);
PAINT WHITE (-10735 -490);
WIRE 16 -1 (-9075 -2000)(-8975 -2000);
WIRE 16 -1 (-8975 -2000)(-8975 -1525);
WIRE 16 -1 (-8975 -1525)(-8825 -1525);
WIRE 16 -1 (-8825 -1575)(-8825 -1525);
WIRE 16 -1 (-11225 -2300)(-9875 -2300);
FORCEPROP 0 LAST CDS_PHYS_NET_NAME H_CPU_ERR1_LVC1_N
J 0
(-11200 -2258);
PAINT MONO (-11200 -2258);
DISPLAY INVISIBLE (-11200 -2258);
FORCEPROP 0 LAST SIG_NAME H_CPU_ERR1_LVC1_N
J 0
(-11060 -2290);
DISPLAY 0.680851 (-11060 -2290);
PAINT WHITE (-11060 -2290);
WIRE 16 -1 (-8225 -1900)(-8225 -2000);
WIRE 16 -1 (-8225 -2000)(-7850 -2000);
WIRE 16 -1 (-7850 -2000)(-7850 -1900);
WIRE 16 -1 (-9075 -2050)(-8475 -2050);
FORCEPROP 2 LAST SIG_NAME P0V62_CPU0_ERRS_U306_VREF
J 0
(-8984 -2050);
DISPLAY 0.446809 (-8984 -2050);
PAINT WHITE (-8984 -2050);
WIRE 16 -1 (-8475 -2050)(-8475 -1650);
WIRE 16 -1 (-8475 -1650)(-8225 -1650);
WIRE 16 -1 (-8225 -1650)(-8225 -1700);
WIRE 16 -1 (-7850 -1650)(-8225 -1650);
WIRE 16 -1 (-7850 -1650)(-7850 -1700);
WIRE 16 -1 (-7850 -1525)(-7850 -1650);
WIRE 16 2175 (-7950 -1050)(-7375 -1050);
WIRE 16 2175 (-7375 -1050)(-7375 -1975);
WIRE 16 2175 (-7950 -1050)(-7950 -1975);
WIRE 16 2175 (-7950 -1975)(-7375 -1975);
WIRE 16 -1 (-6775 -1800)(-5900 -1800);
WIRE 16 -1 (-6775 -1875)(-6775 -1800);
WIRE 16 -1 (-5900 -1875)(-6775 -1875);
WIRE 16 -1 (-6775 -2250)(-6775 -1875);
WIRE 16 -1 (-9075 -2250)(-6775 -2250);
FORCEPROP 0 LAST CDS_PHYS_NET_NAME RST_CPU0_DRAM_AB_PLD_N
J 0
(-9050 -2208);
PAINT MONO (-9050 -2208);
DISPLAY INVISIBLE (-9050 -2208);
FORCEPROP 0 LAST SIG_NAME H_CPU_ERR0_LVC2_R_N
J 0
(-8985 -2240);
DISPLAY 0.680851 (-8985 -2240);
PAINT WHITE (-8985 -2240);
WIRE 16 -1 (-6700 -2375)(-5900 -2375);
WIRE 16 -1 (-6700 -2300)(-6700 -2375);
WIRE 16 -1 (-6700 -2300)(-5900 -2300);
WIRE 16 -1 (-9075 -2300)(-6700 -2300);
FORCEPROP 0 LAST CDS_PHYS_NET_NAME RST_CPU0_DRAM_CD_PLD_N
J 0
(-9050 -2258);
PAINT MONO (-9050 -2258);
DISPLAY INVISIBLE (-9050 -2258);
FORCEPROP 0 LAST SIG_NAME H_CPU_ERR1_LVC2_R_N
J 0
(-8985 -2290);
DISPLAY 0.680851 (-8985 -2290);
PAINT WHITE (-8985 -2290);
WIRE 16 -1 (-4850 -2375)(-5700 -2375);
FORCEPROP 2 LAST SIG_NAME H_CPU_ERR1_PCH_R_N
J 0
(-5400 -2365);
DISPLAY 0.553191 (-5400 -2365);
PAINT WHITE (-5400 -2365);
WIRE 16 -1 (-5700 -2300)(-4850 -2300);
FORCEPROP 0 LAST CDS_PHYS_NET_NAME RST_CPU0_DRAM_CD_PLD_N
J 0
(-5675 -2258);
PAINT MONO (-5675 -2258);
DISPLAY INVISIBLE (-5675 -2258);
FORCEPROP 0 LAST SIG_NAME H_CPU_ERR1_LVC2_N
J 0
(-5410 -2290);
DISPLAY 0.680851 (-5410 -2290);
PAINT WHITE (-5410 -2290);
WIRE 16 -1 (-7600 -400)(-6175 -400);
FORCEPROP 0 LAST CDS_PHYS_NET_NAME RST_CPU0_DRAM_CD_PLD_N
J 0
(-7575 -358);
PAINT MONO (-7575 -358);
DISPLAY INVISIBLE (-7575 -358);
FORCEPROP 0 LAST SIG_NAME RST_CPU1_DRAM_CD_PLD_LVT3_N
J 0
(-7135 -390);
DISPLAY 0.680851 (-7135 -390);
PAINT WHITE (-7135 -390);
WIRE 16 -1 (-7600 -500)(-6175 -500);
FORCEPROP 0 LAST CDS_PHYS_NET_NAME RST_CPU0_DRAM_GH_PLD_N
J 0
(-7575 -458);
PAINT MONO (-7575 -458);
DISPLAY INVISIBLE (-7575 -458);
FORCEPROP 0 LAST SIG_NAME RST_CPU1_DRAM_GH_PLD_LVT3_N
J 0
(-7135 -490);
DISPLAY 0.680851 (-7135 -490);
PAINT WHITE (-7135 -490);
WIRE 16 2175 (-8025 2000)(-7450 2000);
WIRE 16 2175 (-7450 2925)(-7450 2000);
WIRE 16 2175 (-8025 2925)(-8025 2000);
WIRE 16 2175 (-8025 2925)(-7450 2925);
WIRE 16 -1 (-10875 1625)(-9875 1625);
FORCEPROP 0 LAST CDS_PHYS_NET_NAME RST_CPU0_DRAM_EF_PLD_N
J 0
(-10850 1667);
PAINT MONO (-10850 1667);
DISPLAY INVISIBLE (-10850 1667);
FORCEPROP 0 LAST SIG_NAME RST_CPU0_DRAM_EF_PLD_N
J 0
(-10735 1635);
DISPLAY 0.680851 (-10735 1635);
PAINT WHITE (-10735 1635);
WIRE 16 -1 (-10875 1575)(-9875 1575);
FORCEPROP 0 LAST CDS_PHYS_NET_NAME RST_CPU0_DRAM_GH_PLD_N
J 0
(-10850 1617);
PAINT MONO (-10850 1617);
DISPLAY INVISIBLE (-10850 1617);
FORCEPROP 0 LAST SIG_NAME RST_CPU0_DRAM_GH_PLD_N
J 0
(-10735 1585);
DISPLAY 0.680851 (-10735 1585);
PAINT WHITE (-10735 1585);
WIRE 16 2175 (-8025 -75)(-7450 -75);
WIRE 16 2175 (-7450 850)(-7450 -75);
WIRE 16 2175 (-8025 850)(-8025 -75);
WIRE 16 2175 (-8025 850)(-7450 850);
WIRE 16 -1 (-7850 1975)(-7850 2075);
WIRE 16 -1 (-8225 1975)(-7850 1975);
WIRE 16 -1 (-8225 2075)(-8225 1975);
WIRE 16 -1 (-7700 1875)(-7925 1875);
WIRE 16 -1 (-7925 1825)(-9075 1825);
FORCEPROP 2 LAST SIG_NAME PD_GTL2014_BMC_JTAG_DIR_0
J 0
(-8950 1835);
DISPLAY 0.446809 (-8950 1835);
PAINT WHITE (-8950 1835);
WIRE 16 -1 (-7925 1825)(-7925 1875);
WIRE 16 -1 (-7125 1875)(-7500 1875);
WIRE 16 -1 (-7850 2325)(-7850 2275);
WIRE 16 -1 (-7850 2450)(-7850 2325);
WIRE 16 -1 (-8225 2325)(-8225 2275);
WIRE 16 -1 (-7850 2325)(-8225 2325);
WIRE 16 -1 (-8350 2325)(-8225 2325);
WIRE 16 -1 (-8350 1925)(-8350 2325);
WIRE 16 -1 (-9075 1925)(-8350 1925);
FORCEPROP 2 LAST SIG_NAME P0V62_CPU0_RST_DDR_VREF
J 0
(-8950 1935);
DISPLAY 0.446809 (-8950 1935);
PAINT WHITE (-8950 1935);
WIRE 16 -1 (-9075 1625)(-7800 1625);
FORCEPROP 0 LAST CDS_PHYS_NET_NAME RST_CPU0_DRAM_EF_PLD_N
J 0
(-9050 1667);
PAINT MONO (-9050 1667);
DISPLAY INVISIBLE (-9050 1667);
FORCEPROP 0 LAST SIG_NAME RST_CPU0_DRAM_EF_PLD_LVT3_R_N
J 0
(-8935 1635);
DISPLAY 0.680851 (-8935 1635);
PAINT WHITE (-8935 1635);
WIRE 16 -1 (-9075 1725)(-7800 1725);
FORCEPROP 0 LAST CDS_PHYS_NET_NAME RST_CPU0_DRAM_AB_PLD_N
J 0
(-9050 1767);
PAINT MONO (-9050 1767);
DISPLAY INVISIBLE (-9050 1767);
FORCEPROP 0 LAST SIG_NAME RST_CPU0_DRAM_AB_PLD_LVT3_R_N
J 0
(-8935 1735);
DISPLAY 0.680851 (-8935 1735);
PAINT WHITE (-8935 1735);
WIRE 16 -1 (-8525 -2400)(-9075 -2400);
FORCEPROP 2 LAST SIG_NAME NC_U306_A0
J 0
(-8985 -2390);
DISPLAY 0.638298 (-8985 -2390);
PAINT WHITE (-8985 -2390);
WIRE 16 -1 (-9075 -2350)(-6775 -2350);
FORCEPROP 0 LAST CDS_PHYS_NET_NAME RST_CPU0_DRAM_EF_PLD_N
J 0
(-9050 -2308);
PAINT MONO (-9050 -2308);
DISPLAY INVISIBLE (-9050 -2308);
FORCEPROP 0 LAST SIG_NAME H_CPU_ERR2_LVC2_R_N
J 0
(-8985 -2340);
DISPLAY 0.680851 (-8985 -2340);
PAINT WHITE (-8985 -2340);
WIRE 16 -1 (-6775 -2350)(-6775 -2800);
WIRE 16 -1 (-6775 -2800)(-5900 -2800);
WIRE 16 -1 (-6775 -2800)(-6775 -2875);
WIRE 16 -1 (-6775 -2875)(-5900 -2875);
WIRE 16 -1 (-7675 -2150)(-9075 -2150);
FORCEPROP 2 LAST SIG_NAME PD_CPU1_ERRS_U306_DIR
J 0
(-8984 -2150);
DISPLAY 0.446809 (-8984 -2150);
PAINT WHITE (-8984 -2150);
WIRE 16 -1 (-9875 -2400)(-10425 -2400);
FORCEPROP 2 LAST SIG_NAME PD_GTL2014_ERROR_B0
J 0
(-10485 -2390);
DISPLAY 0.638298 (-10485 -2390);
PAINT WHITE (-10485 -2390);
WIRE 16 -1 (-10425 -2925)(-10425 -2400);
WIRE 16 -1 (-9875 -2600)(-10000 -2600);
WIRE 16 -1 (-10000 -2550)(-10000 -2600);
WIRE 16 -1 (-10000 -2550)(-9875 -2550);
WIRE 16 -1 (-10000 -2500)(-10000 -2550);
WIRE 16 -1 (-10000 -2500)(-9875 -2500);
WIRE 16 -1 (-10875 1725)(-9875 1725);
FORCEPROP 0 LAST CDS_PHYS_NET_NAME RST_CPU0_DRAM_AB_PLD_N
J 0
(-10850 1767);
PAINT MONO (-10850 1767);
DISPLAY INVISIBLE (-10850 1767);
FORCEPROP 0 LAST SIG_NAME RST_CPU0_DRAM_AB_PLD_N
J 0
(-10735 1735);
DISPLAY 0.680851 (-10735 1735);
PAINT WHITE (-10735 1735);
WIRE 16 -1 (-10875 1675)(-9875 1675);
FORCEPROP 0 LAST CDS_PHYS_NET_NAME RST_CPU0_DRAM_CD_PLD_N
J 0
(-10850 1717);
PAINT MONO (-10850 1717);
DISPLAY INVISIBLE (-10850 1717);
FORCEPROP 0 LAST SIG_NAME RST_CPU0_DRAM_CD_PLD_N
J 0
(-10735 1685);
DISPLAY 0.680851 (-10735 1685);
PAINT WHITE (-10735 1685);
WIRE 16 -1 (-4875 -1875)(-5700 -1875);
FORCEPROP 2 LAST SIG_NAME H_CPU_ERR0_PCH_R_N
J 0
(-5400 -1865);
DISPLAY 0.553191 (-5400 -1865);
PAINT WHITE (-5400 -1865);
WIRE 16 -1 (-5700 -1800)(-4875 -1800);
FORCEPROP 0 LAST CDS_PHYS_NET_NAME H_CPU_ERR0_LVC2_N
J 0
(-5675 -1758);
PAINT MONO (-5675 -1758);
DISPLAY INVISIBLE (-5675 -1758);
FORCEPROP 0 LAST SIG_NAME H_CPU_ERR0_LVC2_N
J 0
(-5410 -1790);
DISPLAY 0.680851 (-5410 -1790);
PAINT WHITE (-5410 -1790);
WIRE 16 -1 (-5700 -2800)(-4850 -2800);
FORCEPROP 0 LAST CDS_PHYS_NET_NAME H_CPU_ERR2_LVC2_N
J 0
(-5675 -2758);
PAINT MONO (-5675 -2758);
DISPLAY INVISIBLE (-5675 -2758);
FORCEPROP 0 LAST SIG_NAME H_CPU_ERR2_LVC2_N
J 0
(-5410 -2790);
DISPLAY 0.680851 (-5410 -2790);
PAINT WHITE (-5410 -2790);
WIRE 16 -1 (-4850 -2875)(-5700 -2875);
FORCEPROP 2 LAST SIG_NAME H_CPU_ERR2_PCH_R_N
J 0
(-5400 -2865);
DISPLAY 0.553191 (-5400 -2865);
PAINT WHITE (-5400 -2865);
WIRE 16 -1 (-9075 1575)(-7800 1575);
FORCEPROP 0 LAST CDS_PHYS_NET_NAME RST_CPU0_DRAM_GH_PLD_N
J 0
(-9050 1617);
PAINT MONO (-9050 1617);
DISPLAY INVISIBLE (-9050 1617);
FORCEPROP 0 LAST SIG_NAME RST_CPU0_DRAM_GH_PLD_LVT3_R_N
J 0
(-8935 1585);
DISPLAY 0.680851 (-8935 1585);
PAINT WHITE (-8935 1585);
WIRE 16 -1 (-9075 1675)(-7800 1675);
FORCEPROP 0 LAST CDS_PHYS_NET_NAME RST_CPU0_DRAM_CD_PLD_N
J 0
(-9050 1717);
PAINT MONO (-9050 1717);
DISPLAY INVISIBLE (-9050 1717);
FORCEPROP 0 LAST SIG_NAME RST_CPU0_DRAM_CD_PLD_LVT3_R_N
J 0
(-8935 1685);
DISPLAY 0.680851 (-8935 1685);
PAINT WHITE (-8935 1685);
WIRE 16 -1 (-7500 -200)(-7125 -200);
WIRE 16 -1 (-7600 -350)(-6175 -350);
FORCEPROP 0 LAST CDS_PHYS_NET_NAME RST_CPU0_DRAM_AB_PLD_N
J 0
(-7575 -308);
PAINT MONO (-7575 -308);
DISPLAY INVISIBLE (-7575 -308);
FORCEPROP 0 LAST SIG_NAME RST_CPU1_DRAM_AB_PLD_LVT3_N
J 0
(-7135 -340);
DISPLAY 0.680851 (-7135 -340);
PAINT WHITE (-7135 -340);
WIRE 16 -1 (-11225 -3150)(-10500 -3150);
FORCEPROP 0 LAST SIG_NAME H_CPU_ERR2_LVC1_N
J 0
(-11085 -3140);
DISPLAY 0.680851 (-11085 -3140);
PAINT WHITE (-11085 -3140);
WIRE 16 -1 (-10500 -3150)(-10500 -2350);
WIRE 16 -1 (-10500 -2350)(-9875 -2350);
FORCEPROP 0 LAST CDS_PHYS_NET_NAME H_CPU_ERR2_LVC1_N
J 0
(-10475 -2308);
PAINT MONO (-10475 -2308);
DISPLAY INVISIBLE (-10475 -2308);
WIRE 16 -1 (-7850 -100)(-7850 0);
WIRE 16 -1 (-8225 -100)(-7850 -100);
WIRE 16 -1 (-8225 0)(-8225 -100);
WIRE 16 -1 (-12350 -1325)(-12050 -1325);
WIRE 16 -1 (-12050 -1150)(-12050 -1325);
WIRE 16 -1 (-12050 -1375)(-12350 -1375);
WIRE 16 -1 (-12050 -1325)(-12050 -1375);
WIRE 16 -1 (-12050 -1375)(-11425 -1375);
FORCEPROP 2 LAST SIG_NAME H_CPU_ERR0_LVC1_R_N
J 0
(-12030 -1375);
DISPLAY 0.553191 (-12030 -1375);
PAINT WHITE (-12030 -1375);
WIRE 16 -1 (-12300 -3100)(-12075 -3100);
WIRE 16 -1 (-12075 -2925)(-12075 -3100);
WIRE 16 -1 (-12075 -3100)(-12075 -3150);
WIRE 16 -1 (-12075 -3150)(-11425 -3150);
FORCEPROP 2 LAST SIG_NAME H_CPU_ERR2_LVC1_R_N
J 0
(-12030 -3150);
DISPLAY 0.553191 (-12030 -3150);
PAINT WHITE (-12030 -3150);
WIRE 16 -1 (-12300 -3150)(-12075 -3150);
WIRE 16 -1 (-12500 -3150)(-13175 -3150);
FORCEPROP 2 LAST SIG_NAME H_CPU1_ERR2_LVC1_R_N
J 0
(-13160 -3140);
DISPLAY 0.553191 (-13160 -3140);
PAINT WHITE (-13160 -3140);
WIRE 16 -1 (-12550 -1375)(-13225 -1375);
FORCEPROP 2 LAST SIG_NAME H_CPU1_ERR0_LVC1_R_N
J 0
(-13210 -1365);
DISPLAY 0.553191 (-13210 -1365);
PAINT WHITE (-13210 -1365);
WIRE 16 -1 (-12375 -2250)(-12075 -2250);
WIRE 16 -1 (-12075 -2075)(-12075 -2250);
WIRE 16 -1 (-12075 -2250)(-12075 -2300);
WIRE 16 -1 (-12075 -2300)(-11425 -2300);
FORCEPROP 2 LAST SIG_NAME H_CPU_ERR1_LVC1_R_N
J 0
(-12029 -2300);
DISPLAY 0.553191 (-12029 -2300);
PAINT WHITE (-12029 -2300);
WIRE 16 -1 (-12375 -2300)(-12075 -2300);
WIRE 16 -1 (-12550 -1325)(-13225 -1325);
FORCEPROP 2 LAST SIG_NAME H_CPU0_ERR0_LVC1_R_N
J 0
(-13210 -1315);
DISPLAY 0.553191 (-13210 -1315);
PAINT WHITE (-13210 -1315);
WIRE 16 -1 (-12575 -2250)(-13250 -2250);
FORCEPROP 2 LAST SIG_NAME H_CPU0_ERR1_LVC1_R_N
J 0
(-13235 -2240);
DISPLAY 0.553191 (-13235 -2240);
PAINT WHITE (-13235 -2240);
WIRE 16 -1 (-12575 -2300)(-13250 -2300);
FORCEPROP 2 LAST SIG_NAME H_CPU1_ERR1_LVC1_R_N
J 0
(-13235 -2290);
DISPLAY 0.553191 (-13235 -2290);
PAINT WHITE (-13235 -2290);
WIRE 16 -1 (-12500 -3100)(-13175 -3100);
FORCEPROP 2 LAST SIG_NAME H_CPU0_ERR2_LVC1_R_N
J 0
(-13160 -3090);
DISPLAY 0.553191 (-13160 -3090);
PAINT WHITE (-13160 -3090);
WIRE 16 -1 (-9075 1975)(-8975 1975);
WIRE 16 -1 (-8975 1975)(-8975 2450);
WIRE 16 -1 (-8975 2450)(-8825 2450);
WIRE 16 -1 (-8825 2400)(-8825 2450);
WIRE 16 -1 (-9875 1375)(-10000 1375);
WIRE 16 -1 (-10000 1425)(-10000 1375);
WIRE 16 -1 (-10000 1425)(-9875 1425);
WIRE 16 -1 (-10000 1475)(-10000 1425);
WIRE 16 -1 (-10000 1475)(-9875 1475);
WIRE 16 -1 (-7475 -2100)(-7475 -2150);
WIRE 16 -1 (-7475 -2100)(-7125 -2100);
WIRE 16 -1 (-7600 1575)(-6175 1575);
FORCEPROP 0 LAST CDS_PHYS_NET_NAME RST_CPU0_DRAM_GH_PLD_N
J 0
(-7575 1617);
PAINT MONO (-7575 1617);
DISPLAY INVISIBLE (-7575 1617);
FORCEPROP 0 LAST SIG_NAME RST_CPU0_DRAM_GH_PLD_LVT3_N
J 0
(-7135 1585);
DISPLAY 0.680851 (-7135 1585);
PAINT WHITE (-7135 1585);
WIRE 16 -1 (-7600 1725)(-6175 1725);
FORCEPROP 0 LAST CDS_PHYS_NET_NAME RST_CPU0_DRAM_AB_PLD_N
J 0
(-7575 1767);
PAINT MONO (-7575 1767);
DISPLAY INVISIBLE (-7575 1767);
FORCEPROP 0 LAST SIG_NAME RST_CPU0_DRAM_AB_PLD_LVT3_N
J 0
(-7135 1735);
DISPLAY 0.680851 (-7135 1735);
PAINT WHITE (-7135 1735);
WIRE 16 -1 (-7600 1675)(-6175 1675);
FORCEPROP 0 LAST CDS_PHYS_NET_NAME RST_CPU0_DRAM_CD_PLD_N
J 0
(-7575 1717);
PAINT MONO (-7575 1717);
DISPLAY INVISIBLE (-7575 1717);
FORCEPROP 0 LAST SIG_NAME RST_CPU0_DRAM_CD_PLD_LVT3_N
J 0
(-7135 1685);
DISPLAY 0.680851 (-7135 1685);
PAINT WHITE (-7135 1685);
WIRE 16 -1 (-7600 1625)(-6175 1625);
FORCEPROP 0 LAST CDS_PHYS_NET_NAME RST_CPU0_DRAM_EF_PLD_N
J 0
(-7575 1667);
PAINT MONO (-7575 1667);
DISPLAY INVISIBLE (-7575 1667);
FORCEPROP 0 LAST SIG_NAME RST_CPU0_DRAM_EF_PLD_LVT3_N
J 0
(-7135 1635);
DISPLAY 0.680851 (-7135 1635);
PAINT WHITE (-7135 1635);
WIRE 16 -1 (-7600 -450)(-6175 -450);
FORCEPROP 0 LAST CDS_PHYS_NET_NAME RST_CPU0_DRAM_EF_PLD_N
J 0
(-7575 -408);
PAINT MONO (-7575 -408);
DISPLAY INVISIBLE (-7575 -408);
FORCEPROP 0 LAST SIG_NAME RST_CPU1_DRAM_EF_PLD_LVT3_N
J 0
(-7135 -440);
DISPLAY 0.680851 (-7135 -440);
PAINT WHITE (-7135 -440);
DOT 1 (-7850 -2000);
DOT 1 (-8225 -1650);
DOT 1 (-7850 2325);
DOT 1 (-10000 -2550);
DOT 1 (-10000 -700);
DOT 1 (-10000 -2600);
DOT 1 (-12050 -1375);
DOT 1 (-12050 -1325);
DOT 1 (-12075 -2250);
DOT 1 (-12075 -2300);
DOT 1 (-12075 -3100);
DOT 1 (-12075 -3150);
DOT 1 (-6700 -2300);
DOT 1 (-6775 -2800);
DOT 1 (-6775 -1875);
DOT 1 (-7850 -1650);
DOT 1 (-7850 250);
DOT 1 (-10000 1375);
DOT 1 (-10000 -650);
DOT 1 (-8225 2325);
DOT 1 (-10000 1425);
DOT 1 (-8975 -1525);
DOT 1 (-8225 250);
DOT 1 (-7850 -100);
DOT 1 (-8975 375);
DOT 1 (-8975 2450);
DOT 1 (-7850 1975);
FORCENOTE
20211206 CHANGE R4038,R4041
(-7325 -1150) 0;
DISPLAY LEFT (-7325 -1150);
DISPLAY 1.595745 (-7325 -1150);
PAINT PINK (-7325 -1150);
FORCENOTE
20211206 CHANGE R4037,R4040
(-7400 750) 0;
DISPLAY LEFT (-7400 750);
DISPLAY 1.595745 (-7400 750);
PAINT PINK (-7400 750);
FORCENOTE
20211206 CHANGE R4036,R4039
(-7425 2850) 0;
DISPLAY LEFT (-7425 2850);
DISPLAY 1.595745 (-7425 2850);
PAINT PINK (-7425 2850);
FORCENOTE
20210902 MODIFY FOR GT
(-13350 2800) 0;
DISPLAY LEFT (-13350 2800);
DISPLAY 2.510638 (-13350 2800);
PAINT PINK (-13350 2800);
QUIT
